G04 ================== begin FILE IDENTIFICATION RECORD ==================*
G04 Layout Name:  15105-sa.brd*
G04 Film Name:    TMASK*
G04 File Format:  Gerber RS274X*
G04 File Origin:  Cadence Allegro 16.5-S056*
G04 Origin Date:  Wed Nov 16 02:01:53 2016*
G04 *
G04 Layer:  VIA CLASS/SOLDERMASK_TOP*
G04 Layer:  PIN/SOLDERMASK_TOP*
G04 Layer:  PACKAGE GEOMETRY/SOLDERMASK_TOP*
G04 Layer:  DRAWING FORMAT/LAYER_PCB_STORY*
G04 Layer:  DRAWING FORMAT/LAYER_SOLDER_T*
G04 Layer:  BOARD GEOMETRY/SOLDERMASK_TOP*
G04 *
G04 Offset:    (0.00 0.00)*
G04 Mirror:    No*
G04 Mode:      Positive*
G04 Rotation:  0*
G04 FullContactRelief:  No*
G04 UndefLineWidth:     6.00*
G04 ================== end FILE IDENTIFICATION RECORD ====================*
%FSLAX35Y35*MOIN*%
%IR0*IPPOS*OFA0.00000B0.00000*MIA0B0*SFA1.00000B1.00000*%
%AMMACRO41*
4,1,40,.013,.017,
-.013,.017,
-.013695,.016939,
-.014368,.016759,
-.015,.016464,
-.015571,.016064,
-.016064,.015571,
-.016464,.015,
-.016759,.014368,
-.016939,.013695,
-.017,.013,
-.017,-.013,
-.016939,-.013695,
-.016759,-.014368,
-.016464,-.015,
-.016064,-.015571,
-.015571,-.016064,
-.015,-.016464,
-.014368,-.016759,
-.013695,-.016939,
-.013,-.017,
.013,-.017,
.013695,-.016939,
.014368,-.016759,
.015,-.016464,
.015571,-.016064,
.016064,-.015571,
.016464,-.015,
.016759,-.014368,
.016939,-.013695,
.017,-.013,
.017,.013,
.016939,.013695,
.016759,.014368,
.016464,.015,
.016064,.015571,
.015571,.016064,
.015,.016464,
.014368,.016759,
.013695,.016939,
.013,.017,
0.0*
%
%ADD41MACRO41*%
%AMMACRO26*
4,1,40,.017,-.013,
.017,.013,
.016939,.013695,
.016759,.014368,
.016464,.015,
.016064,.015571,
.015571,.016064,
.015,.016464,
.014368,.016759,
.013695,.016939,
.013,.017,
-.013,.017,
-.013695,.016939,
-.014368,.016759,
-.015,.016464,
-.015571,.016064,
-.016064,.015571,
-.016464,.015,
-.016759,.014368,
-.016939,.013695,
-.017,.013,
-.017,-.013,
-.016939,-.013695,
-.016759,-.014368,
-.016464,-.015,
-.016064,-.015571,
-.015571,-.016064,
-.015,-.016464,
-.014368,-.016759,
-.013695,-.016939,
-.013,-.017,
.013,-.017,
.013695,-.016939,
.014368,-.016759,
.015,-.016464,
.015571,-.016064,
.016064,-.015571,
.016464,-.015,
.016759,-.014368,
.016939,-.013695,
.017,-.013,
0.0*
%
%ADD26MACRO26*%
%AMMACRO80*
4,1,15,-.0275,-.115,
-.0275,.02323,
-.02431,.026923,
-.021809,.031114,
-.020074,.035675,
-.019157,.040469,
-.019087,.045348,
-.019865,.050166,
-.021468,.054776,
-.023847,.059037,
-.02693,.06282,
-.0275,.06339,
-.0275,.115,
.0275,.115,
.0275,-.115,
-.0275,-.115,
0.0*
%
%ADD80MACRO80*%
%ADD94R,.081X.1*%
%ADD115R,.045X.11*%
%ADD142R,.055X.11*%
%ADD101R,.111X.028*%
%ADD75R,.012X.008*%
%ADD55C,.02*%
%ADD126C,.04*%
%ADD149C,.05*%
%ADD64C,.032*%
%ADD52C,.014*%
%ADD144R,.008X.06*%
%AMMACRO69*
4,1,40,.004,.007,
-.004,.007,
-.004347,.00697,
-.004684,.006879,
-.005,.006732,
-.005286,.006532,
-.005532,.006286,
-.005732,.006,
-.005879,.005684,
-.00597,.005347,
-.006,.005,
-.006,-.005,
-.00597,-.005347,
-.005879,-.005684,
-.005732,-.006,
-.005532,-.006286,
-.005286,-.006532,
-.005,-.006732,
-.004684,-.006879,
-.004347,-.00697,
-.004,-.007,
.004,-.007,
.004347,-.00697,
.004684,-.006879,
.005,-.006732,
.005286,-.006532,
.005532,-.006286,
.005732,-.006,
.005879,-.005684,
.00597,-.005347,
.006,-.005,
.006,.005,
.00597,.005347,
.005879,.005684,
.005732,.006,
.005532,.006286,
.005286,.006532,
.005,.006732,
.004684,.006879,
.004347,.00697,
.004,.007,
0.0*
%
%ADD69MACRO69*%
%ADD82C,.016*%
%ADD39C,.052*%
%ADD139R,.092X.128*%
%ADD125R,.039X.108*%
%ADD37C,.08*%
%ADD148C,.018*%
%ADD122C,.036*%
%ADD79C,.054*%
%ADD29C,.028*%
%ADD151C,.038*%
%ADD124C,.029*%
%ADD100C,.056*%
%ADD134R,.135X.098*%
%ADD11C,.066*%
%ADD120C,.058*%
%ADD10C,.086*%
%ADD147R,.044X.044*%
%AMMACRO113*
4,1,26,-.47244,-.55118,
-.47244,.55118,
.47244,.55118,
.47244,.19704,
.35433,.19704,
.348829,.196559,
.343495,.195129,
.33849,.192796,
.333966,.189628,
.330062,.185724,
.326894,.1812,
.324561,.176195,
.323131,.170861,
.32265,.16536,
.32265,-.1496,
.323131,-.155103,
.324561,-.160439,
.326896,-.165445,
.330064,-.16997,
.33397,-.173876,
.338495,-.177044,
.343501,-.179379,
.348837,-.180809,
.35433,-.18129,
.47244,-.18129,
.47244,-.55118,
-.47244,-.55118,
0.0*
%
%ADD113MACRO113*%
%AMMACRO31*
4,1,40,.0225,-.007,
.022378,-.008389,
.022018,-.009736,
.021428,-.011,
.020628,-.012142,
.019642,-.013128,
.0185,-.013928,
.017236,-.014518,
.015889,-.014878,
.0145,-.015,
-.0145,-.015,
-.015889,-.014878,
-.017236,-.014518,
-.0185,-.013928,
-.019642,-.013128,
-.020628,-.012142,
-.021428,-.011,
-.022018,-.009736,
-.022378,-.008389,
-.0225,-.007,
-.0225,.007,
-.022378,.008389,
-.022018,.009736,
-.021428,.011,
-.020628,.012142,
-.019642,.013128,
-.0185,.013928,
-.017236,.014518,
-.015889,.014878,
-.0145,.015,
.0145,.015,
.015889,.014878,
.017236,.014518,
.0185,.013928,
.019642,.013128,
.020628,.012142,
.021428,.011,
.022018,.009736,
.022378,.008389,
.0225,.007,
.0225,-.007,
0.0*
%
%ADD31MACRO31*%
%ADD14C,.078*%
%ADD143R,.045X.045*%
%AMMACRO67*
4,1,40,-.007,-.0225,
-.008389,-.022378,
-.009736,-.022018,
-.011,-.021428,
-.012142,-.020628,
-.013128,-.019642,
-.013928,-.0185,
-.014518,-.017236,
-.014878,-.015889,
-.015,-.0145,
-.015,.0145,
-.014878,.015889,
-.014518,.017236,
-.013928,.0185,
-.013128,.019642,
-.012142,.020628,
-.011,.021428,
-.009736,.022018,
-.008389,.022378,
-.007,.0225,
.007,.0225,
.008389,.022378,
.009736,.022018,
.011,.021428,
.012142,.020628,
.013128,.019642,
.013928,.0185,
.014518,.017236,
.014878,.015889,
.015,.0145,
.015,-.0145,
.014878,-.015889,
.014518,-.017236,
.013928,-.0185,
.013128,-.019642,
.012142,-.020628,
.011,-.021428,
.009736,-.022018,
.008389,-.022378,
.007,-.0225,
-.007,-.0225,
0.0*
%
%ADD67MACRO67*%
%AMMACRO32*
4,1,40,.007,.011,
-.007,.011,
-.007695,.010939,
-.008368,.010759,
-.009,.010464,
-.009571,.010064,
-.010064,.009571,
-.010464,.009,
-.010759,.008368,
-.010939,.007695,
-.011,.007,
-.011,-.007,
-.010939,-.007695,
-.010759,-.008368,
-.010464,-.009,
-.010064,-.009571,
-.009571,-.010064,
-.009,-.010464,
-.008368,-.010759,
-.007695,-.010939,
-.007,-.011,
.007,-.011,
.007695,-.010939,
.008368,-.010759,
.009,-.010464,
.009571,-.010064,
.010064,-.009571,
.010464,-.009,
.010759,-.008368,
.010939,-.007695,
.011,-.007,
.011,.007,
.010939,.007695,
.010759,.008368,
.010464,.009,
.010064,.009571,
.009571,.010064,
.009,.010464,
.008368,.010759,
.007695,.010939,
.007,.011,
0.0*
%
%ADD32MACRO32*%
%AMMACRO23*
4,1,40,.011,-.007,
.011,.007,
.010939,.007695,
.010759,.008368,
.010464,.009,
.010064,.009571,
.009571,.010064,
.009,.010464,
.008368,.010759,
.007695,.010939,
.007,.011,
-.007,.011,
-.007695,.010939,
-.008368,.010759,
-.009,.010464,
-.009571,.010064,
-.010064,.009571,
-.010464,.009,
-.010759,.008368,
-.010939,.007695,
-.011,.007,
-.011,-.007,
-.010939,-.007695,
-.010759,-.008368,
-.010464,-.009,
-.010064,-.009571,
-.009571,-.010064,
-.009,-.010464,
-.008368,-.010759,
-.007695,-.010939,
-.007,-.011,
.007,-.011,
.007695,-.010939,
.008368,-.010759,
.009,-.010464,
.009571,-.010064,
.010064,-.009571,
.010464,-.009,
.010759,-.008368,
.010939,-.007695,
.011,-.007,
0.0*
%
%ADD23MACRO23*%
%AMMACRO53*
4,1,20,.032,-.047,
.0155,-.047,
.0155,-.074,
.0045,-.074,
.0045,-.049,
-.0045,-.049,
-.0045,-.074,
-.0155,-.074,
-.0155,-.047,
-.032,-.047,
-.032,.047,
-.0155,.047,
-.0155,.074,
-.0045,.074,
-.0045,.049,
.0045,.049,
.0045,.074,
.0155,.074,
.0155,.047,
.032,.047,
.032,-.047,
0.0*
%
%ADD53MACRO53*%
%AMMACRO130*
4,1,40,-.012,.024,
.012,.024,
.013389,.023878,
.014736,.023518,
.016,.022928,
.017142,.022128,
.018128,.021142,
.018928,.02,
.019518,.018736,
.019878,.017389,
.02,.016,
.02,-.016,
.019878,-.017389,
.019518,-.018736,
.018928,-.02,
.018128,-.021142,
.017142,-.022128,
.016,-.022928,
.014736,-.023518,
.013389,-.023878,
.012,-.024,
-.012,-.024,
-.013389,-.023878,
-.014736,-.023518,
-.016,-.022928,
-.017142,-.022128,
-.018128,-.021142,
-.018928,-.02,
-.019518,-.018736,
-.019878,-.017389,
-.02,-.016,
-.02,.016,
-.019878,.017389,
-.019518,.018736,
-.018928,.02,
-.018128,.021142,
-.017142,.022128,
-.016,.022928,
-.014736,.023518,
-.013389,.023878,
-.012,.024,
0.0*
%
%ADD130MACRO130*%
%AMMACRO129*
4,1,20,-.047,-.032,
-.047,-.0155,
-.074,-.0155,
-.074,-.0045,
-.049,-.0045,
-.049,.0045,
-.074,.0045,
-.074,.0155,
-.047,.0155,
-.047,.032,
.047,.032,
.047,.0155,
.074,.0155,
.074,.0045,
.049,.0045,
.049,-.0045,
.074,-.0045,
.074,-.0155,
.047,-.0155,
.047,-.032,
-.047,-.032,
0.0*
%
%ADD129MACRO129*%
%AMMACRO158*
4,1,45,.43011,.54331,
-.43012,.54331,
-.43012,-.5433,
.43011,-.5433,
.43011,-.19684,
.429811,-.193423,
.428923,-.190109,
.427473,-.187,
.425506,-.18419,
.42308,-.181764,
.42027,-.179797,
.417161,-.178347,
.413847,-.177459,
.41043,-.17716,
.39665,-.17716,
.393231,-.176859,
.389916,-.175969,
.386806,-.174517,
.383996,-.172547,
.38157,-.170119,
.379603,-.167306,
.378154,-.164195,
.377267,-.160879,
.37697,-.15747,
.37697,.15749,
.377269,.160907,
.378157,.164221,
.379607,.16733,
.381574,.17014,
.384,.172566,
.38681,.174533,
.389919,.175983,
.393233,.176871,
.39665,.17717,
.41043,.17717,
.413847,.177469,
.417161,.178357,
.42027,.179807,
.42308,.181774,
.425506,.1842,
.427473,.18701,
.428923,.190119,
.429811,.193433,
.43011,.19685,
.43011,.19686,
.43011,.54331,
0.0*
%
%ADD158MACRO158*%
%AMMACRO49*
4,1,40,-.012,.008,
-.012,-.008,
-.011939,-.008695,
-.011759,-.009368,
-.011464,-.01,
-.011064,-.010571,
-.010571,-.011064,
-.01,-.011464,
-.009368,-.011759,
-.008695,-.011939,
-.008,-.012,
.008,-.012,
.008695,-.011939,
.009368,-.011759,
.01,-.011464,
.010571,-.011064,
.011064,-.010571,
.011464,-.01,
.011759,-.009368,
.011939,-.008695,
.012,-.008,
.012,.008,
.011939,.008695,
.011759,.009368,
.011464,.01,
.011064,.010571,
.010571,.011064,
.01,.011464,
.009368,.011759,
.008695,.011939,
.008,.012,
-.008,.012,
-.008695,.011939,
-.009368,.011759,
-.01,.011464,
-.010571,.011064,
-.011064,.010571,
-.011464,.01,
-.011759,.009368,
-.011939,.008695,
-.012,.008,
0.0*
%
%ADD49MACRO49*%
%AMMACRO12*
4,1,40,.008,.012,
-.008,.012,
-.008695,.011939,
-.009368,.011759,
-.01,.011464,
-.010571,.011064,
-.011064,.010571,
-.011464,.01,
-.011759,.009368,
-.011939,.008695,
-.012,.008,
-.012,-.008,
-.011939,-.008695,
-.011759,-.009368,
-.011464,-.01,
-.011064,-.010571,
-.010571,-.011064,
-.01,-.011464,
-.009368,-.011759,
-.008695,-.011939,
-.008,-.012,
.008,-.012,
.008695,-.011939,
.009368,-.011759,
.01,-.011464,
.010571,-.011064,
.011064,-.010571,
.011464,-.01,
.011759,-.009368,
.011939,-.008695,
.012,-.008,
.012,.008,
.011939,.008695,
.011759,.009368,
.011464,.01,
.011064,.010571,
.010571,.011064,
.01,.011464,
.009368,.011759,
.008695,.011939,
.008,.012,
0.0*
%
%ADD12MACRO12*%
%AMMACRO42*
4,1,40,-.013,-.017,
.013,-.017,
.013695,-.016939,
.014368,-.016759,
.015,-.016464,
.015571,-.016064,
.016064,-.015571,
.016464,-.015,
.016759,-.014368,
.016939,-.013695,
.017,-.013,
.017,.013,
.016939,.013695,
.016759,.014368,
.016464,.015,
.016064,.015571,
.015571,.016064,
.015,.016464,
.014368,.016759,
.013695,.016939,
.013,.017,
-.013,.017,
-.013695,.016939,
-.014368,.016759,
-.015,.016464,
-.015571,.016064,
-.016064,.015571,
-.016464,.015,
-.016759,.014368,
-.016939,.013695,
-.017,.013,
-.017,-.013,
-.016939,-.013695,
-.016759,-.014368,
-.016464,-.015,
-.016064,-.015571,
-.015571,-.016064,
-.015,-.016464,
-.014368,-.016759,
-.013695,-.016939,
-.013,-.017,
0.0*
%
%ADD42MACRO42*%
%AMMACRO131*
4,1,6,-.025,-.0135,
-.005,.0065,
-.005,.0135,
.005,.0135,
.005,.0065,
.025,-.0135,
-.025,-.0135,
0.0*
%
%ADD131MACRO131*%
%AMMACRO18*
4,1,40,-.017,.013,
-.017,-.013,
-.016939,-.013695,
-.016759,-.014368,
-.016464,-.015,
-.016064,-.015571,
-.015571,-.016064,
-.015,-.016464,
-.014368,-.016759,
-.013695,-.016939,
-.013,-.017,
.013,-.017,
.013695,-.016939,
.014368,-.016759,
.015,-.016464,
.015571,-.016064,
.016064,-.015571,
.016464,-.015,
.016759,-.014368,
.016939,-.013695,
.017,-.013,
.017,.013,
.016939,.013695,
.016759,.014368,
.016464,.015,
.016064,.015571,
.015571,.016064,
.015,.016464,
.014368,.016759,
.013695,.016939,
.013,.017,
-.013,.017,
-.013695,.016939,
-.014368,.016759,
-.015,.016464,
-.015571,.016064,
-.016064,.015571,
-.016464,.015,
-.016759,.014368,
-.016939,.013695,
-.017,.013,
0.0*
%
%ADD18MACRO18*%
%AMMACRO107*
4,1,6,.005,.0135,
.005,.0065,
.025,-.0135,
-.025,-.0135,
-.005,.0065,
-.005,.0135,
.005,.0135,
0.0*
%
%ADD107MACRO107*%
%AMMACRO33*
4,1,40,.007,.011,
-.007,.011,
-.007695,.010939,
-.008368,.010759,
-.009,.010464,
-.009571,.010064,
-.010064,.009571,
-.010464,.009,
-.010759,.008368,
-.010939,.007695,
-.011,.007,
-.011,-.007,
-.010939,-.007695,
-.010759,-.008368,
-.010464,-.009,
-.010064,-.009571,
-.009571,-.010064,
-.009,-.010464,
-.008368,-.010759,
-.007695,-.010939,
-.007,-.011,
.007,-.011,
.007695,-.010939,
.008368,-.010759,
.009,-.010464,
.009571,-.010064,
.010064,-.009571,
.010464,-.009,
.010759,-.008368,
.010939,-.007695,
.011,-.007,
.011,.007,
.010939,.007695,
.010759,.008368,
.010464,.009,
.010064,.009571,
.009571,.010064,
.009,.010464,
.008368,.010759,
.007695,.010939,
.007,.011,
0.0*
%
%ADD33MACRO33*%
%AMMACRO24*
4,1,40,.011,-.007,
.011,.007,
.010939,.007695,
.010759,.008368,
.010464,.009,
.010064,.009571,
.009571,.010064,
.009,.010464,
.008368,.010759,
.007695,.010939,
.007,.011,
-.007,.011,
-.007695,.010939,
-.008368,.010759,
-.009,.010464,
-.009571,.010064,
-.010064,.009571,
-.010464,.009,
-.010759,.008368,
-.010939,.007695,
-.011,.007,
-.011,-.007,
-.010939,-.007695,
-.010759,-.008368,
-.010464,-.009,
-.010064,-.009571,
-.009571,-.010064,
-.009,-.010464,
-.008368,-.010759,
-.007695,-.010939,
-.007,-.011,
.007,-.011,
.007695,-.010939,
.008368,-.010759,
.009,-.010464,
.009571,-.010064,
.010064,-.009571,
.010464,-.009,
.010759,-.008368,
.010939,-.007695,
.011,-.007,
0.0*
%
%ADD24MACRO24*%
%AMMACRO159*
4,1,20,.0635,-.1075,
.049,-.1075,
.049,-.118,
.0395,-.118,
.0395,-.1075,
-.0395,-.1075,
-.0395,-.118,
-.049,-.118,
-.049,-.1075,
-.0635,-.1075,
-.0635,.1075,
-.049,.1075,
-.049,.118,
-.0395,.118,
-.0395,.1075,
.0395,.1075,
.0395,.118,
.049,.118,
.049,.1075,
.0635,.1075,
.0635,-.1075,
0.0*
%
%ADD159MACRO159*%
%AMMACRO22*
4,1,40,-.012,.008,
-.012,-.008,
-.011939,-.008695,
-.011759,-.009368,
-.011464,-.01,
-.011064,-.010571,
-.010571,-.011064,
-.01,-.011464,
-.009368,-.011759,
-.008695,-.011939,
-.008,-.012,
.008,-.012,
.008695,-.011939,
.009368,-.011759,
.01,-.011464,
.010571,-.011064,
.011064,-.010571,
.011464,-.01,
.011759,-.009368,
.011939,-.008695,
.012,-.008,
.012,.008,
.011939,.008695,
.011759,.009368,
.011464,.01,
.011064,.010571,
.010571,.011064,
.01,.011464,
.009368,.011759,
.008695,.011939,
.008,.012,
-.008,.012,
-.008695,.011939,
-.009368,.011759,
-.01,.011464,
-.010571,.011064,
-.011064,.010571,
-.011464,.01,
-.011759,.009368,
-.011939,.008695,
-.012,.008,
0.0*
%
%ADD22MACRO22*%
%AMMACRO13*
4,1,40,.008,.012,
-.008,.012,
-.008695,.011939,
-.009368,.011759,
-.01,.011464,
-.010571,.011064,
-.011064,.010571,
-.011464,.01,
-.011759,.009368,
-.011939,.008695,
-.012,.008,
-.012,-.008,
-.011939,-.008695,
-.011759,-.009368,
-.011464,-.01,
-.011064,-.010571,
-.010571,-.011064,
-.01,-.011464,
-.009368,-.011759,
-.008695,-.011939,
-.008,-.012,
.008,-.012,
.008695,-.011939,
.009368,-.011759,
.01,-.011464,
.010571,-.011064,
.011064,-.010571,
.011464,-.01,
.011759,-.009368,
.011939,-.008695,
.012,-.008,
.012,.008,
.011939,.008695,
.011759,.009368,
.011464,.01,
.011064,.010571,
.010571,.011064,
.01,.011464,
.009368,.011759,
.008695,.011939,
.008,.012,
0.0*
%
%ADD13MACRO13*%
%AMMACRO43*
4,1,40,-.013,-.017,
.013,-.017,
.013695,-.016939,
.014368,-.016759,
.015,-.016464,
.015571,-.016064,
.016064,-.015571,
.016464,-.015,
.016759,-.014368,
.016939,-.013695,
.017,-.013,
.017,.013,
.016939,.013695,
.016759,.014368,
.016464,.015,
.016064,.015571,
.015571,.016064,
.015,.016464,
.014368,.016759,
.013695,.016939,
.013,.017,
-.013,.017,
-.013695,.016939,
-.014368,.016759,
-.015,.016464,
-.015571,.016064,
-.016064,.015571,
-.016464,.015,
-.016759,.014368,
-.016939,.013695,
-.017,.013,
-.017,-.013,
-.016939,-.013695,
-.016759,-.014368,
-.016464,-.015,
-.016064,-.015571,
-.015571,-.016064,
-.015,-.016464,
-.014368,-.016759,
-.013695,-.016939,
-.013,-.017,
0.0*
%
%ADD43MACRO43*%
%AMMACRO17*
4,1,40,-.017,.013,
-.017,-.013,
-.016939,-.013695,
-.016759,-.014368,
-.016464,-.015,
-.016064,-.015571,
-.015571,-.016064,
-.015,-.016464,
-.014368,-.016759,
-.013695,-.016939,
-.013,-.017,
.013,-.017,
.013695,-.016939,
.014368,-.016759,
.015,-.016464,
.015571,-.016064,
.016064,-.015571,
.016464,-.015,
.016759,-.014368,
.016939,-.013695,
.017,-.013,
.017,.013,
.016939,.013695,
.016759,.014368,
.016464,.015,
.016064,.015571,
.015571,.016064,
.015,.016464,
.014368,.016759,
.013695,.016939,
.013,.017,
-.013,.017,
-.013695,.016939,
-.014368,.016759,
-.015,.016464,
-.015571,.016064,
-.016064,.015571,
-.016464,.015,
-.016759,.014368,
-.016939,.013695,
-.017,.013,
0.0*
%
%ADD17MACRO17*%
%ADD154R,.135X.21*%
%ADD76R,.012X.022*%
%ADD138R,.041X.012*%
%ADD136R,.012X.041*%
%ADD30R,.04X.022*%
%ADD118R,.06X.012*%
%ADD90R,.02X.06*%
%ADD51R,.022X.04*%
%ADD81R,.023X.04*%
%ADD60R,.012X.042*%
%ADD58R,.042X.012*%
%ADD108R,.044X.012*%
%ADD104R,.06X.014*%
%ADD103R,.04X.016*%
%ADD119O,.046X.041*%
%ADD116R,.014X.06*%
%ADD114R,.105X.128*%
%ADD56R,.016X.04*%
%ADD47R,.012X.036*%
%ADD46R,.036X.012*%
%ADD140R,.041X.053*%
%ADD137R,.037X.012*%
%ADD135R,.012X.037*%
%ADD123C,.103*%
%ADD97R,.06X.016*%
%ADD77R,.03X.045*%
%ADD59R,.012X.036*%
%ADD57R,.036X.012*%
%ADD48R,.012X.046*%
%ADD45R,.046X.012*%
%ADD155R,.028X.03*%
%ADD96R,.012X.038*%
%ADD95R,.038X.012*%
%ADD84R,.03X.064*%
%ADD83R,.016X.06*%
%ADD109R,.02X.066*%
%ADD88R,.022X.091*%
%ADD133R,.042X.055*%
%ADD102R,.05X.065*%
%ADD93R,.104X.187*%
%ADD87R,.022X.074*%
%ADD145R,.037X.042*%
%ADD99R,.02X.059*%
%ADD78C,.107*%
%ADD74R,.065X.05*%
%ADD146R,.044X.028*%
%ADD111R,.065X.025*%
%ADD98R,.036X.026*%
%ADD36C,.315*%
%ADD153R,.028X.044*%
%ADD85R,.09X.045*%
%ADD71R,.048X.016*%
%ADD70R,.036X.055*%
%ADD54R,.045X.055*%
%ADD50R,.025X.065*%
%ADD68R,.016X.048*%
%ADD61R,.13X.13*%
%ADD38C,.128*%
%ADD25R,.055X.045*%
%ADD128R,.054X.074*%
%ADD92R,.047X.073*%
%ADD91R,.075X.045*%
%ADD44C,.256*%
%ADD89R,.09X.095*%
%ADD86R,.059X.045*%
%ADD63R,.024X.079*%
%ADD21R,.075X.065*%
%AMMACRO121*
4,1,40,-.0225,.007,
-.022378,.008389,
-.022018,.009736,
-.021428,.011,
-.020628,.012142,
-.019642,.013128,
-.0185,.013928,
-.017236,.014518,
-.015889,.014878,
-.0145,.015,
.0145,.015,
.015889,.014878,
.017236,.014518,
.0185,.013928,
.019642,.013128,
.020628,.012142,
.021428,.011,
.022018,.009736,
.022378,.008389,
.0225,.007,
.0225,-.007,
.022378,-.008389,
.022018,-.009736,
.021428,-.011,
.020628,-.012142,
.019642,-.013128,
.0185,-.013928,
.017236,-.014518,
.015889,-.014878,
.0145,-.015,
-.0145,-.015,
-.015889,-.014878,
-.017236,-.014518,
-.0185,-.013928,
-.019642,-.013128,
-.020628,-.012142,
-.021428,-.011,
-.022018,-.009736,
-.022378,-.008389,
-.0225,-.007,
-.0225,.007,
0.0*
%
%ADD121MACRO121*%
%ADD117R,.095X.09*%
%AMMACRO66*
4,1,40,.007,.0225,
.008389,.022378,
.009736,.022018,
.011,.021428,
.012142,.020628,
.013128,.019642,
.013928,.0185,
.014518,.017236,
.014878,.015889,
.015,.0145,
.015,-.0145,
.014878,-.015889,
.014518,-.017236,
.013928,-.0185,
.013128,-.019642,
.012142,-.020628,
.011,-.021428,
.009736,-.022018,
.008389,-.022378,
.007,-.0225,
-.007,-.0225,
-.008389,-.022378,
-.009736,-.022018,
-.011,-.021428,
-.012142,-.020628,
-.013128,-.019642,
-.013928,-.0185,
-.014518,-.017236,
-.014878,-.015889,
-.015,-.0145,
-.015,.0145,
-.014878,.015889,
-.014518,.017236,
-.013928,.0185,
-.013128,.019642,
-.012142,.020628,
-.011,.021428,
-.009736,.022018,
-.008389,.022378,
-.007,.0225,
.007,.0225,
0.0*
%
%ADD66MACRO66*%
%ADD156R,.057X.039*%
%ADD127R,.069X.055*%
%ADD110R,.059X.039*%
%AMMACRO157*
4,1,40,.024,.012,
.024,-.012,
.023878,-.013389,
.023518,-.014736,
.022928,-.016,
.022128,-.017142,
.021142,-.018128,
.02,-.018928,
.018736,-.019518,
.017389,-.019878,
.016,-.02,
-.016,-.02,
-.017389,-.019878,
-.018736,-.019518,
-.02,-.018928,
-.021142,-.018128,
-.022128,-.017142,
-.022928,-.016,
-.023518,-.014736,
-.023878,-.013389,
-.024,-.012,
-.024,.012,
-.023878,.013389,
-.023518,.014736,
-.022928,.016,
-.022128,.017142,
-.021142,.018128,
-.02,.018928,
-.018736,.019518,
-.017389,.019878,
-.016,.02,
.016,.02,
.017389,.019878,
.018736,.019518,
.02,.018928,
.021142,.018128,
.022128,.017142,
.022928,.016,
.023518,.014736,
.023878,.013389,
.024,.012,
0.0*
%
%ADD157MACRO157*%
%AMMACRO152*
4,1,40,.012,-.024,
-.012,-.024,
-.013389,-.023878,
-.014736,-.023518,
-.016,-.022928,
-.017142,-.022128,
-.018128,-.021142,
-.018928,-.02,
-.019518,-.018736,
-.019878,-.017389,
-.02,-.016,
-.02,.016,
-.019878,.017389,
-.019518,.018736,
-.018928,.02,
-.018128,.021142,
-.017142,.022128,
-.016,.022928,
-.014736,.023518,
-.013389,.023878,
-.012,.024,
.012,.024,
.013389,.023878,
.014736,.023518,
.016,.022928,
.017142,.022128,
.018128,.021142,
.018928,.02,
.019518,.018736,
.019878,.017389,
.02,.016,
.02,-.016,
.019878,-.017389,
.019518,-.018736,
.018928,-.02,
.018128,-.021142,
.017142,-.022128,
.016,-.022928,
.014736,-.023518,
.013389,-.023878,
.012,-.024,
0.0*
%
%ADD152MACRO152*%
%AMMACRO112*
4,1,20,-.032,.047,
-.0155,.047,
-.0155,.074,
-.0045,.074,
-.0045,.049,
.0045,.049,
.0045,.074,
.0155,.074,
.0155,.047,
.032,.047,
.032,-.047,
.0155,-.047,
.0155,-.074,
.0045,-.074,
.0045,-.049,
-.0045,-.049,
-.0045,-.074,
-.0155,-.074,
-.0155,-.047,
-.032,-.047,
-.032,.047,
0.0*
%
%ADD112MACRO112*%
%ADD65R,.138X.138*%
%ADD150R,.047X.098*%
%ADD141R,.472X.866*%
%AMMACRO72*
4,1,40,.012,-.008,
.012,.008,
.011939,.008695,
.011759,.009368,
.011464,.01,
.011064,.010571,
.010571,.011064,
.01,.011464,
.009368,.011759,
.008695,.011939,
.008,.012,
-.008,.012,
-.008695,.011939,
-.009368,.011759,
-.01,.011464,
-.010571,.011064,
-.011064,.010571,
-.011464,.01,
-.011759,.009368,
-.011939,.008695,
-.012,.008,
-.012,-.008,
-.011939,-.008695,
-.011759,-.009368,
-.011464,-.01,
-.011064,-.010571,
-.010571,-.011064,
-.01,-.011464,
-.009368,-.011759,
-.008695,-.011939,
-.008,-.012,
.008,-.012,
.008695,-.011939,
.009368,-.011759,
.01,-.011464,
.010571,-.011064,
.011064,-.010571,
.011464,-.01,
.011759,-.009368,
.011939,-.008695,
.012,-.008,
0.0*
%
%ADD72MACRO72*%
%AMMACRO28*
4,1,40,-.007,-.011,
.007,-.011,
.007695,-.010939,
.008368,-.010759,
.009,-.010464,
.009571,-.010064,
.010064,-.009571,
.010464,-.009,
.010759,-.008368,
.010939,-.007695,
.011,-.007,
.011,.007,
.010939,.007695,
.010759,.008368,
.010464,.009,
.010064,.009571,
.009571,.010064,
.009,.010464,
.008368,.010759,
.007695,.010939,
.007,.011,
-.007,.011,
-.007695,.010939,
-.008368,.010759,
-.009,.010464,
-.009571,.010064,
-.010064,.009571,
-.010464,.009,
-.010759,.008368,
-.010939,.007695,
-.011,.007,
-.011,-.007,
-.010939,-.007695,
-.010759,-.008368,
-.010464,-.009,
-.010064,-.009571,
-.009571,-.010064,
-.009,-.010464,
-.008368,-.010759,
-.007695,-.010939,
-.007,-.011,
0.0*
%
%ADD28MACRO28*%
%ADD19R,.089X.096*%
%AMMACRO15*
4,1,40,-.008,-.012,
.008,-.012,
.008695,-.011939,
.009368,-.011759,
.01,-.011464,
.010571,-.011064,
.011064,-.010571,
.011464,-.01,
.011759,-.009368,
.011939,-.008695,
.012,-.008,
.012,.008,
.011939,.008695,
.011759,.009368,
.011464,.01,
.011064,.010571,
.010571,.011064,
.01,.011464,
.009368,.011759,
.008695,.011939,
.008,.012,
-.008,.012,
-.008695,.011939,
-.009368,.011759,
-.01,.011464,
-.010571,.011064,
-.011064,.010571,
-.011464,.01,
-.011759,.009368,
-.011939,.008695,
-.012,.008,
-.012,-.008,
-.011939,-.008695,
-.011759,-.009368,
-.011464,-.01,
-.011064,-.010571,
-.010571,-.011064,
-.01,-.011464,
-.009368,-.011759,
-.008695,-.011939,
-.008,-.012,
0.0*
%
%ADD15MACRO15*%
%AMMACRO34*
4,1,40,-.011,.007,
-.011,-.007,
-.010939,-.007695,
-.010759,-.008368,
-.010464,-.009,
-.010064,-.009571,
-.009571,-.010064,
-.009,-.010464,
-.008368,-.010759,
-.007695,-.010939,
-.007,-.011,
.007,-.011,
.007695,-.010939,
.008368,-.010759,
.009,-.010464,
.009571,-.010064,
.010064,-.009571,
.010464,-.009,
.010759,-.008368,
.010939,-.007695,
.011,-.007,
.011,.007,
.010939,.007695,
.010759,.008368,
.010464,.009,
.010064,.009571,
.009571,.010064,
.009,.010464,
.008368,.010759,
.007695,.010939,
.007,.011,
-.007,.011,
-.007695,.010939,
-.008368,.010759,
-.009,.010464,
-.009571,.010064,
-.010064,.009571,
-.010464,.009,
-.010759,.008368,
-.010939,.007695,
-.011,.007,
0.0*
%
%ADD34MACRO34*%
%AMMACRO106*
4,1,6,.025,.0135,
.005,-.0065,
.005,-.0135,
-.005,-.0135,
-.005,-.0065,
-.025,.0135,
.025,.0135,
0.0*
%
%ADD106MACRO106*%
%AMMACRO40*
4,1,40,.013,.017,
-.013,.017,
-.013695,.016939,
-.014368,.016759,
-.015,.016464,
-.015571,.016064,
-.016064,.015571,
-.016464,.015,
-.016759,.014368,
-.016939,.013695,
-.017,.013,
-.017,-.013,
-.016939,-.013695,
-.016759,-.014368,
-.016464,-.015,
-.016064,-.015571,
-.015571,-.016064,
-.015,-.016464,
-.014368,-.016759,
-.013695,-.016939,
-.013,-.017,
.013,-.017,
.013695,-.016939,
.014368,-.016759,
.015,-.016464,
.015571,-.016064,
.016064,-.015571,
.016464,-.015,
.016759,-.014368,
.016939,-.013695,
.017,-.013,
.017,.013,
.016939,.013695,
.016759,.014368,
.016464,.015,
.016064,.015571,
.015571,.016064,
.015,.016464,
.014368,.016759,
.013695,.016939,
.013,.017,
0.0*
%
%ADD40MACRO40*%
%AMMACRO27*
4,1,40,.017,-.013,
.017,.013,
.016939,.013695,
.016759,.014368,
.016464,.015,
.016064,.015571,
.015571,.016064,
.015,.016464,
.014368,.016759,
.013695,.016939,
.013,.017,
-.013,.017,
-.013695,.016939,
-.014368,.016759,
-.015,.016464,
-.015571,.016064,
-.016064,.015571,
-.016464,.015,
-.016759,.014368,
-.016939,.013695,
-.017,.013,
-.017,-.013,
-.016939,-.013695,
-.016759,-.014368,
-.016464,-.015,
-.016064,-.015571,
-.015571,-.016064,
-.015,-.016464,
-.014368,-.016759,
-.013695,-.016939,
-.013,-.017,
.013,-.017,
.013695,-.016939,
.014368,-.016759,
.015,-.016464,
.015571,-.016064,
.016064,-.015571,
.016464,-.015,
.016759,-.014368,
.016939,-.013695,
.017,-.013,
0.0*
%
%ADD27MACRO27*%
%AMMACRO132*
4,1,6,-.005,-.0135,
-.005,-.0065,
-.025,.0135,
.025,.0135,
.005,-.0065,
.005,-.0135,
-.005,-.0135,
0.0*
%
%ADD132MACRO132*%
%AMMACRO105*
4,1,20,-.0635,.1075,
-.049,.1075,
-.049,.118,
-.0395,.118,
-.0395,.1075,
.0395,.1075,
.0395,.118,
.049,.118,
.049,.1075,
.0635,.1075,
.0635,-.1075,
.049,-.1075,
.049,-.118,
.0395,-.118,
.0395,-.1075,
-.0395,-.1075,
-.0395,-.118,
-.049,-.118,
-.049,-.1075,
-.0635,-.1075,
-.0635,.1075,
0.0*
%
%ADD105MACRO105*%
%AMMACRO73*
4,1,40,.012,-.008,
.012,.008,
.011939,.008695,
.011759,.009368,
.011464,.01,
.011064,.010571,
.010571,.011064,
.01,.011464,
.009368,.011759,
.008695,.011939,
.008,.012,
-.008,.012,
-.008695,.011939,
-.009368,.011759,
-.01,.011464,
-.010571,.011064,
-.011064,.010571,
-.011464,.01,
-.011759,.009368,
-.011939,.008695,
-.012,.008,
-.012,-.008,
-.011939,-.008695,
-.011759,-.009368,
-.011464,-.01,
-.011064,-.010571,
-.010571,-.011064,
-.01,-.011464,
-.009368,-.011759,
-.008695,-.011939,
-.008,-.012,
.008,-.012,
.008695,-.011939,
.009368,-.011759,
.01,-.011464,
.010571,-.011064,
.011064,-.010571,
.011464,-.01,
.011759,-.009368,
.011939,-.008695,
.012,-.008,
0.0*
%
%ADD73MACRO73*%
%AMMACRO62*
4,1,15,-.0275,-.115,
-.0275,.115,
.0275,.115,
.0275,.06339,
.02431,.059697,
.021809,.055506,
.020074,.050945,
.019157,.046151,
.019087,.041272,
.019865,.036454,
.021468,.031844,
.023847,.027583,
.02693,.0238,
.0275,.02323,
.0275,-.115,
-.0275,-.115,
0.0*
%
%ADD62MACRO62*%
%AMMACRO20*
4,1,40,-.007,-.011,
.007,-.011,
.007695,-.010939,
.008368,-.010759,
.009,-.010464,
.009571,-.010064,
.010064,-.009571,
.010464,-.009,
.010759,-.008368,
.010939,-.007695,
.011,-.007,
.011,.007,
.010939,.007695,
.010759,.008368,
.010464,.009,
.010064,.009571,
.009571,.010064,
.009,.010464,
.008368,.010759,
.007695,.010939,
.007,.011,
-.007,.011,
-.007695,.010939,
-.008368,.010759,
-.009,.010464,
-.009571,.010064,
-.010064,.009571,
-.010464,.009,
-.010759,.008368,
-.010939,.007695,
-.011,.007,
-.011,-.007,
-.010939,-.007695,
-.010759,-.008368,
-.010464,-.009,
-.010064,-.009571,
-.009571,-.010064,
-.009,-.010464,
-.008368,-.010759,
-.007695,-.010939,
-.007,-.011,
0.0*
%
%ADD20MACRO20*%
%AMMACRO16*
4,1,40,-.008,-.012,
.008,-.012,
.008695,-.011939,
.009368,-.011759,
.01,-.011464,
.010571,-.011064,
.011064,-.010571,
.011464,-.01,
.011759,-.009368,
.011939,-.008695,
.012,-.008,
.012,.008,
.011939,.008695,
.011759,.009368,
.011464,.01,
.011064,.010571,
.010571,.011064,
.01,.011464,
.009368,.011759,
.008695,.011939,
.008,.012,
-.008,.012,
-.008695,.011939,
-.009368,.011759,
-.01,.011464,
-.010571,.011064,
-.011064,.010571,
-.011464,.01,
-.011759,.009368,
-.011939,.008695,
-.012,.008,
-.012,-.008,
-.011939,-.008695,
-.011759,-.009368,
-.011464,-.01,
-.011064,-.010571,
-.010571,-.011064,
-.01,-.011464,
-.009368,-.011759,
-.008695,-.011939,
-.008,-.012,
0.0*
%
%ADD16MACRO16*%
%AMMACRO35*
4,1,40,-.011,.007,
-.011,-.007,
-.010939,-.007695,
-.010759,-.008368,
-.010464,-.009,
-.010064,-.009571,
-.009571,-.010064,
-.009,-.010464,
-.008368,-.010759,
-.007695,-.010939,
-.007,-.011,
.007,-.011,
.007695,-.010939,
.008368,-.010759,
.009,-.010464,
.009571,-.010064,
.010064,-.009571,
.010464,-.009,
.010759,-.008368,
.010939,-.007695,
.011,-.007,
.011,.007,
.010939,.007695,
.010759,.008368,
.010464,.009,
.010064,.009571,
.009571,.010064,
.009,.010464,
.008368,.010759,
.007695,.010939,
.007,.011,
-.007,.011,
-.007695,.010939,
-.008368,.010759,
-.009,.010464,
-.009571,.010064,
-.010064,.009571,
-.010464,.009,
-.010759,.008368,
-.010939,.007695,
-.011,.007,
0.0*
%
%ADD35MACRO35*%
%ADD160C,.006*%
G75*
%LPD*%
G75*
G36*
G01X112000Y786615D02*
X120550D01*
Y795565D01*
X112000D01*
Y786615D01*
G37*
G36*
G01X100850D02*
X109400D01*
Y795565D01*
X100850D01*
Y786615D01*
G37*
G36*
G01X112000Y798165D02*
X120550D01*
Y807115D01*
X112000D01*
Y798165D01*
G37*
G36*
G01X100850D02*
X109400D01*
Y807115D01*
X100850D01*
Y798165D01*
G37*
G36*
G01X443214Y897938D02*
X111905D01*
Y883420D01*
X443214D01*
Y897938D01*
G37*
G36*
G01X860537D02*
X529228D01*
Y883420D01*
X860537D01*
Y897938D01*
G37*
G36*
G01X1356600D02*
X1025291D01*
Y883420D01*
X1356600D01*
Y897938D01*
G37*
G54D100*
X193900Y274372D03*
X183900D03*
X213900D03*
X203900D03*
X302500Y207200D03*
X292500D03*
X326200D03*
X336200D03*
X312500D03*
X346200D03*
X465485Y200680D03*
Y190680D03*
Y180680D03*
X488462Y180761D03*
Y190761D03*
Y200761D03*
X501742Y215594D03*
X511742D03*
X521742D03*
X531742D03*
X772300Y16200D03*
X762300D03*
X752300D03*
X785300Y16100D03*
X795300D03*
X805300D03*
X819291Y265354D03*
Y285354D03*
X1075197Y92126D03*
Y112126D03*
X1348785Y161642D03*
X1323195D03*
X1348785Y179358D03*
X1323195D03*
G54D110*
X235500Y439000D03*
Y449000D03*
Y469000D03*
Y459000D03*
Y479000D03*
Y499000D03*
Y489000D03*
G54D101*
X235713Y73589D03*
Y68589D03*
Y63589D03*
Y103589D03*
Y98589D03*
Y93589D03*
Y88589D03*
Y83589D03*
Y78589D03*
Y108589D03*
Y118589D03*
Y113589D03*
X250181Y73589D03*
Y68589D03*
Y63589D03*
Y103589D03*
Y98589D03*
Y93589D03*
Y88589D03*
Y83589D03*
Y78589D03*
Y108589D03*
Y118589D03*
Y113589D03*
G54D111*
X263488Y578165D03*
Y583165D03*
Y588165D03*
Y593165D03*
X293229Y343640D03*
Y338640D03*
Y333640D03*
Y328640D03*
X273229D03*
Y333640D03*
Y338640D03*
Y343640D03*
X283488Y578165D03*
Y593165D03*
Y588165D03*
Y583165D03*
X493909Y324041D03*
Y329041D03*
Y334041D03*
Y339041D03*
X513909D03*
Y334041D03*
Y329041D03*
Y324041D03*
X875000Y31000D03*
Y36000D03*
Y41000D03*
Y46000D03*
X895000Y41000D03*
Y36000D03*
Y31000D03*
Y46000D03*
X1001300Y55400D03*
Y60400D03*
Y65400D03*
Y70400D03*
X1021300D03*
Y65400D03*
Y60400D03*
Y55400D03*
G54D102*
X228800Y160600D03*
X217800D03*
X464389Y324210D03*
X475389D03*
G54D120*
X473231Y235560D03*
Y274930D03*
X487404Y255245D03*
G54D112*
X259300Y635900D03*
G54D121*
X478719Y308208D03*
X486219Y312083D03*
X478719Y315958D03*
X733382Y3881D03*
Y-3869D03*
X740882Y6D03*
X873250Y22375D03*
Y14625D03*
X880750Y18500D03*
X1306970Y139185D03*
Y131435D03*
X1314470Y135310D03*
G54D103*
X215338Y436405D03*
Y433845D03*
Y431285D03*
X207938Y436405D03*
Y433845D03*
Y431285D03*
X249800Y348840D03*
Y351400D03*
Y353960D03*
X257200Y348840D03*
Y351400D03*
Y353960D03*
X257600Y433160D03*
Y430600D03*
Y428040D03*
X250200Y433160D03*
Y430600D03*
Y428040D03*
X269000Y501360D03*
Y498800D03*
Y496240D03*
X276400D03*
Y498800D03*
Y501360D03*
Y508440D03*
Y511000D03*
X269000D03*
Y508440D03*
X276400Y513560D03*
X269000D03*
G54D130*
X598808Y205137D03*
X602808Y213937D03*
X606808Y205137D03*
G54D10*
X700Y19100D03*
X16200Y120100D03*
X27200Y821800D03*
X33800Y872600D03*
X1384200Y122800D03*
X1373200Y823500D03*
X1415100Y-36700D03*
X1389800Y879000D03*
G54D20*
X28148Y310872D03*
X28212Y306674D03*
X21800Y424000D03*
X29300Y429000D03*
X30600Y533500D03*
X25100Y720400D03*
X41600Y321400D03*
X36800Y466000D03*
X57400Y470100D03*
Y474200D03*
X63569Y502220D03*
X37300Y484500D03*
X55400Y713000D03*
X97900Y272000D03*
X95607Y281582D03*
X76291Y365075D03*
X76105Y360727D03*
X85700Y360000D03*
X80990Y392665D03*
X93649Y477241D03*
X79569Y513090D03*
X80444Y508831D03*
X92300Y506000D03*
X80444Y504831D03*
X92300Y526500D03*
Y522500D03*
Y530500D03*
X79569Y517090D03*
X92300Y534500D03*
Y518500D03*
Y538500D03*
X80800Y534300D03*
Y538300D03*
X67720Y535931D03*
Y531831D03*
X80300Y606500D03*
X73800Y582000D03*
X79900Y681900D03*
X87500D03*
X75800Y723200D03*
X79600Y753700D03*
Y757900D03*
X107100Y212200D03*
X106100Y230100D03*
X100800Y294900D03*
Y290900D03*
X100490Y319780D03*
X100540Y315650D03*
X100700Y324100D03*
X100600Y328600D03*
X123000Y392300D03*
X99200Y732300D03*
X114800Y756000D03*
X132480Y311214D03*
X154100Y402200D03*
X162627Y447721D03*
X143369Y636620D03*
X133851Y648436D03*
X137200Y727800D03*
X164000Y753400D03*
X156800Y808500D03*
X179139Y450747D03*
X196300Y729500D03*
Y785000D03*
X207749Y143587D03*
X202900Y251000D03*
X213500Y446000D03*
X219800Y469000D03*
Y465000D03*
X209800Y478000D03*
X218300Y486600D03*
X209800Y502000D03*
Y506000D03*
X223950Y491200D03*
X223962Y495300D03*
X209800Y534500D03*
Y542500D03*
Y538500D03*
Y550500D03*
Y570500D03*
X222672Y563994D03*
X248400Y339700D03*
X261529Y334140D03*
X257500Y443300D03*
X277800Y126000D03*
X285340Y149350D03*
X277800Y145500D03*
X294288Y578165D03*
Y583165D03*
Y588665D03*
X309082Y293550D03*
X333100Y318900D03*
X315700Y538300D03*
X344000Y335600D03*
X483260Y13180D03*
X483270Y26720D03*
X483300Y49880D03*
Y73380D03*
X469960Y143008D03*
X490900Y166000D03*
X473000Y393300D03*
X504242Y130547D03*
X535012Y159035D03*
X534925Y163463D03*
X505100Y186500D03*
X550780Y133550D03*
X545999Y291069D03*
X558331Y342980D03*
X581363Y228608D03*
X589763Y211308D03*
X619863Y209608D03*
X627463Y209408D03*
Y217608D03*
X622163Y238108D03*
X627463Y213508D03*
X605000Y348200D03*
X652300Y340100D03*
X659800D03*
X652300Y344600D03*
Y372100D03*
Y376600D03*
X659800D03*
X652300Y367100D03*
Y362100D03*
Y352600D03*
Y348600D03*
X733100Y14000D03*
X735400Y114020D03*
X735380Y109410D03*
X756400Y35100D03*
Y26200D03*
X764200D03*
X753800Y64000D03*
X767500Y74000D03*
X757900Y98800D03*
Y94700D03*
X765500Y129400D03*
Y125300D03*
X797610Y26343D03*
X784200Y74100D03*
X806800Y82400D03*
X806900Y94600D03*
Y98700D03*
X773600Y135200D03*
X827860Y105630D03*
X811725Y123631D03*
Y127631D03*
X860500Y3900D03*
X861800Y28000D03*
Y36000D03*
X862300Y8000D03*
X871300Y52800D03*
X862133Y44034D03*
X904800Y33000D03*
Y29000D03*
Y41000D03*
X900300Y341600D03*
Y363000D03*
Y354000D03*
X927270Y23540D03*
X984717Y18587D03*
X1033621Y26921D03*
X1011778Y49109D03*
X1048786Y11208D03*
X1075776Y18266D03*
X1074300Y68500D03*
X1054660Y69355D03*
X1062483Y48832D03*
X1087300Y500D03*
Y5000D03*
X1086920Y27440D03*
X1087304Y36383D03*
X1086920Y22940D03*
X1087304Y40883D03*
X1086525Y14177D03*
X1086727Y18525D03*
X1244784Y145217D03*
X1246268Y141179D03*
X1310110Y145310D03*
X1310826Y151199D03*
X1289300Y295000D03*
X1325300Y290500D03*
X1317300Y294000D03*
X1363218Y168102D03*
G54D140*
X764698Y0D03*
X775460D03*
G54D104*
X204910Y586660D03*
Y589220D03*
Y591780D03*
Y594340D03*
X221090D03*
Y591780D03*
Y589220D03*
Y586660D03*
X773638Y98060D03*
Y95500D03*
Y92940D03*
Y90380D03*
Y87820D03*
Y85260D03*
Y82700D03*
Y80140D03*
X795838D03*
Y82700D03*
Y85260D03*
Y87820D03*
Y90380D03*
Y92940D03*
Y95500D03*
Y98060D03*
X776538Y129460D03*
Y126900D03*
Y124340D03*
Y121780D03*
Y119220D03*
Y116660D03*
Y114100D03*
Y111540D03*
X798738D03*
Y114100D03*
Y116660D03*
Y119220D03*
Y121780D03*
Y124340D03*
Y126900D03*
Y129460D03*
G54D131*
X603363Y221358D03*
G54D113*
X320669Y55118D03*
G54D11*
X31977Y126614D03*
Y116614D03*
X91189Y126614D03*
Y116614D03*
Y136614D03*
G54D122*
X514309Y-315D03*
Y52087D03*
X530057Y106457D03*
X557616Y-315D03*
Y52087D03*
X547773Y106457D03*
X600923Y-315D03*
Y52087D03*
X591080Y106457D03*
X573364D03*
X634388D03*
X616671D03*
X644230Y-315D03*
Y52087D03*
X659978Y106457D03*
X687537Y-315D03*
Y52087D03*
X677695Y106457D03*
X1116671Y-315D03*
Y52087D03*
X1132419Y106457D03*
X1159978Y-315D03*
Y52087D03*
X1175726Y106457D03*
X1150135D03*
X1203285Y-315D03*
Y52087D03*
X1193442Y106457D03*
X1246592Y-315D03*
Y52087D03*
X1236750Y106457D03*
X1219033D03*
X1280057D03*
X1262340D03*
X1289899Y-315D03*
Y52087D03*
G54D105*
X259500Y152000D03*
X602763Y240858D03*
G54D132*
X603363Y223858D03*
G54D141*
X785950Y259820D03*
G54D150*
X1041108Y1702D03*
X1031265D03*
X1050951D03*
G54D21*
X27470Y330307D03*
Y350307D03*
X43262Y330307D03*
Y350307D03*
G54D123*
X535962Y37520D03*
X579269D03*
X622577D03*
X665884D03*
X1138324D03*
X1181631D03*
X1224939D03*
X1268246D03*
G54D114*
X302943Y166500D03*
X281057D03*
X938457Y44100D03*
X960343D03*
G54D30*
X25000Y527062D03*
X34000D03*
X119500Y768500D03*
X128500D03*
G54D12*
X22000Y171200D03*
X48400Y269200D03*
X38500Y280800D03*
X47300Y709600D03*
X72300Y261900D03*
X95223Y388904D03*
X68500Y420700D03*
X74000Y561200D03*
X80500Y562700D03*
X84000D03*
X98500Y598200D03*
X81000Y582200D03*
X81500Y634200D03*
X74600Y727500D03*
X104050Y131660D03*
X100900Y177800D03*
X121799Y359964D03*
X108400Y388400D03*
X118351Y574636D03*
X113851D03*
X145809Y574830D03*
X152319Y574920D03*
X159751Y574836D03*
X153700Y732600D03*
X150200D03*
X146500Y787700D03*
X143000D03*
X186000Y708700D03*
X182500D03*
X186000Y764200D03*
X182500D03*
X205200Y196300D03*
X213500Y510200D03*
X209500D03*
X221000Y518200D03*
X246500Y525700D03*
X282300Y499400D03*
X459200Y372500D03*
X462700D03*
X515950Y130260D03*
X519450D03*
X524450D03*
X527950D03*
X532950D03*
X536450D03*
X525409Y320741D03*
X541450Y130260D03*
X544950D03*
X554400Y339300D03*
X600800Y130100D03*
X588000Y130200D03*
X584500D03*
X577730Y130180D03*
X574300D03*
X593000Y130200D03*
X596500D03*
X604300Y130100D03*
X638000Y130200D03*
X634500D03*
X627676D03*
X624176D03*
X609500Y364313D03*
X646000Y130200D03*
X642500D03*
X861752Y14200D03*
X858252D03*
X854500Y45700D03*
X878800Y52800D03*
X1043418Y32166D03*
X1142000Y130200D03*
X1138500D03*
X1161407Y130854D03*
X1157907D03*
X1199500Y130200D03*
X1196000D03*
X1190935Y130248D03*
X1207949Y130130D03*
X1204449D03*
X1187435Y130248D03*
X1178661Y130327D03*
X1182161D03*
X1243000Y130200D03*
X1239500D03*
X1234309Y130312D03*
X1230809D03*
X1225448Y130309D03*
X1221948D03*
X1277365Y130022D03*
X1273865D03*
X1258544Y130119D03*
X1262044D03*
X1296117Y129827D03*
X1292617D03*
X1286643Y129930D03*
X1283143D03*
X1319000Y278700D03*
X1378160Y181001D03*
G54D160*
G01X145579Y-328699D02*
Y-346199D01*
X154313D01*
G01X167446Y-334533D02*
Y-346199D01*
G01Y-329866D02*
X167009Y-329574D01*
Y-328991D01*
X167446Y-328699D01*
X167883Y-328991D01*
Y-329574D01*
X167446Y-329866D01*
G01X181889Y-350574D02*
X183418Y-351741D01*
X185164Y-352032D01*
X186692Y-351741D01*
X188003Y-350283D01*
X188876Y-348241D01*
Y-334533D01*
G01Y-336866D02*
X188003Y-335699D01*
X186692Y-334824D01*
X185164Y-334533D01*
X183418Y-335116D01*
X182326Y-336282D01*
X181452Y-338324D01*
X181016Y-340366D01*
X181234Y-342116D01*
X182108Y-344158D01*
X183418Y-345616D01*
X185164Y-346199D01*
X186474Y-345907D01*
X188003Y-344741D01*
X188876Y-343575D01*
G01X198734Y-346199D02*
Y-328699D01*
G01Y-337157D02*
X199826Y-335699D01*
X200918Y-334824D01*
X202664Y-334533D01*
X203974Y-334824D01*
X205503Y-335991D01*
X206158Y-337741D01*
Y-346199D01*
G01X219946Y-328699D02*
Y-346199D01*
G01X216889Y-334533D02*
X223003D01*
G01X233734Y-346199D02*
Y-334533D01*
G01Y-337449D02*
X234608Y-335991D01*
X235918Y-334824D01*
X237664Y-334533D01*
X239192Y-334824D01*
X240503Y-335991D01*
X241158Y-338032D01*
Y-346199D01*
G01X254946Y-334533D02*
Y-346199D01*
G01Y-329866D02*
X254509Y-329574D01*
Y-328991D01*
X254946Y-328699D01*
X255383Y-328991D01*
Y-329574D01*
X254946Y-329866D01*
G01X268734Y-346199D02*
Y-334533D01*
G01Y-337449D02*
X269608Y-335991D01*
X270918Y-334824D01*
X272664Y-334533D01*
X274192Y-334824D01*
X275503Y-335991D01*
X276158Y-338032D01*
Y-346199D01*
G01X286889Y-350574D02*
X288418Y-351741D01*
X290164Y-352032D01*
X291692Y-351741D01*
X293003Y-350283D01*
X293876Y-348241D01*
Y-334533D01*
G01Y-336866D02*
X293003Y-335699D01*
X291692Y-334824D01*
X290164Y-334533D01*
X288418Y-335116D01*
X287326Y-336282D01*
X286452Y-338324D01*
X286016Y-340366D01*
X286234Y-342116D01*
X287108Y-344158D01*
X288418Y-345616D01*
X290164Y-346199D01*
X291474Y-345907D01*
X293003Y-344741D01*
X293876Y-343575D01*
G01X320579Y-346199D02*
Y-328699D01*
X325819D01*
X327566Y-329574D01*
X328876Y-331616D01*
X329313Y-333949D01*
X328876Y-336282D01*
X327784Y-338032D01*
X325819Y-338908D01*
X320579D01*
G01X346813Y-346199D02*
X338079D01*
Y-328699D01*
X346813D01*
G01X343319Y-337157D02*
X338079D01*
G01X361692Y-336866D02*
X362566Y-335991D01*
X363221Y-334533D01*
X363658Y-332490D01*
X363221Y-330741D01*
X362348Y-329574D01*
X360819Y-328699D01*
X354924D01*
Y-346199D01*
X362129D01*
X363658Y-345033D01*
X364531Y-343282D01*
X364968Y-341241D01*
X364531Y-339199D01*
X363221Y-337449D01*
X361692Y-336866D01*
X354924D01*
G01X390579Y-346199D02*
Y-328699D01*
X395819D01*
X397566Y-329574D01*
X398876Y-331616D01*
X399313Y-333949D01*
X398876Y-336282D01*
X397784Y-338032D01*
X395819Y-338908D01*
X390579D01*
G01X406769Y-346199D02*
Y-328699D01*
X412446Y-343282D01*
X418123Y-328699D01*
Y-346199D01*
G01X434749Y-330158D02*
X433439Y-329282D01*
X431911Y-328699D01*
X430164D01*
X428199Y-329574D01*
X426671Y-331032D01*
X425579Y-332783D01*
X424706Y-335699D01*
X424487Y-338324D01*
X424924Y-340949D01*
X425579Y-342699D01*
X426889Y-344449D01*
X428418Y-345616D01*
X429946Y-346199D01*
X431474D01*
X433003Y-345616D01*
X434313Y-344741D01*
X435405Y-343575D01*
G01X460579Y-346199D02*
Y-328699D01*
X465819D01*
X467566Y-329574D01*
X468876Y-331616D01*
X469313Y-333949D01*
X468876Y-336282D01*
X467784Y-338032D01*
X465819Y-338908D01*
X460579D01*
G01X476987Y-328699D02*
X482446Y-346199D01*
X487905Y-328699D01*
G01X499946D02*
Y-346199D01*
G01X494924Y-328699D02*
X504968D01*
G01X284269Y-301199D02*
Y-283699D01*
X289946Y-298282D01*
X295623Y-283699D01*
Y-301199D01*
G01X307446D02*
X306136Y-300907D01*
X304826Y-299741D01*
X303952Y-297699D01*
X303516Y-295366D01*
X303952Y-293032D01*
X304826Y-290991D01*
X306136Y-289824D01*
X307446Y-289533D01*
X308756Y-289824D01*
X310066Y-290991D01*
X310939Y-293032D01*
X311158Y-295366D01*
X310939Y-297699D01*
X310066Y-299741D01*
X308756Y-300907D01*
X307446Y-301199D01*
G01X328876Y-283699D02*
Y-301199D01*
G01Y-298575D02*
X328003Y-300033D01*
X326692Y-300907D01*
X325164Y-301199D01*
X323418Y-300616D01*
X322108Y-299158D01*
X321234Y-297408D01*
X321016Y-295366D01*
X321234Y-293324D01*
X322108Y-291574D01*
X323418Y-290116D01*
X325164Y-289533D01*
X326692Y-289824D01*
X327784Y-290408D01*
X328876Y-291574D01*
G01X339171Y-293324D02*
X346158D01*
X345503Y-291282D01*
X344411Y-290116D01*
X342883Y-289533D01*
X341354Y-289824D01*
X340044Y-290699D01*
X339171Y-292741D01*
X338734Y-294491D01*
Y-296241D01*
X339171Y-297991D01*
X340263Y-299741D01*
X341573Y-300907D01*
X343101Y-301199D01*
X344629Y-300616D01*
X346158Y-298866D01*
G01X359946Y-301199D02*
Y-283699D01*
G01X556346Y-346199D02*
Y-328699D01*
X553726Y-332199D01*
G01Y-346199D02*
X558966D01*
G01X569043Y-343575D02*
X570352Y-345033D01*
X571881Y-345907D01*
X573846Y-346199D01*
X575811Y-345616D01*
X577339Y-344449D01*
X578431Y-342408D01*
X578649Y-340074D01*
X578213Y-337741D01*
X577121Y-336282D01*
X575592Y-335116D01*
X574064Y-334824D01*
X572536Y-335116D01*
X570571Y-336282D01*
X571226Y-328699D01*
X577121D01*
G01X591346Y-346199D02*
Y-328699D01*
X588726Y-332199D01*
G01Y-346199D02*
X593966D01*
G01X608846Y-328699D02*
X607099Y-329282D01*
X605789Y-330741D01*
X604916Y-332490D01*
X604261Y-334824D01*
X604043Y-337449D01*
X604261Y-340074D01*
X604916Y-342408D01*
X605789Y-344158D01*
X607099Y-345616D01*
X608846Y-346199D01*
X610592Y-345616D01*
X611903Y-344158D01*
X612776Y-342408D01*
X613431Y-340074D01*
X613649Y-337449D01*
X613431Y-334824D01*
X612776Y-332490D01*
X611903Y-330741D01*
X610592Y-329282D01*
X608846Y-328699D01*
G01X621543Y-343575D02*
X622852Y-345033D01*
X624381Y-345907D01*
X626346Y-346199D01*
X628311Y-345616D01*
X629839Y-344449D01*
X630931Y-342408D01*
X631149Y-340074D01*
X630713Y-337741D01*
X629621Y-336282D01*
X628092Y-335116D01*
X626564Y-334824D01*
X625036Y-335116D01*
X623071Y-336282D01*
X623726Y-328699D01*
X629621D01*
G01X543229Y-301199D02*
Y-283699D01*
X548469D01*
X550216Y-284574D01*
X551526Y-286616D01*
X551963Y-288949D01*
X551526Y-291282D01*
X550434Y-293032D01*
X548469Y-293908D01*
X543229D01*
G01X569899Y-285158D02*
X568589Y-284282D01*
X567061Y-283699D01*
X565314D01*
X563349Y-284574D01*
X561821Y-286032D01*
X560729Y-287783D01*
X559856Y-290699D01*
X559637Y-293324D01*
X560074Y-295949D01*
X560729Y-297699D01*
X562039Y-299449D01*
X563568Y-300616D01*
X565096Y-301199D01*
X566624D01*
X568153Y-300616D01*
X569463Y-299741D01*
X570555Y-298575D01*
G01X584342Y-291866D02*
X585216Y-290991D01*
X585871Y-289533D01*
X586308Y-287490D01*
X585871Y-285741D01*
X584998Y-284574D01*
X583469Y-283699D01*
X577574D01*
Y-301199D01*
X584779D01*
X586308Y-300033D01*
X587181Y-298282D01*
X587618Y-296241D01*
X587181Y-294199D01*
X585871Y-292449D01*
X584342Y-291866D01*
X577574D01*
G01X593546Y-307032D02*
X606646D01*
G01X612574Y-301199D02*
Y-283699D01*
X622618Y-301199D01*
Y-283699D01*
G01X635096Y-301199D02*
X633349Y-300907D01*
X631821Y-299741D01*
X630511Y-297991D01*
X629637Y-295949D01*
X629201Y-293616D01*
Y-291282D01*
X629637Y-288949D01*
X630511Y-286907D01*
X631821Y-285158D01*
X633349Y-283991D01*
X635096Y-283699D01*
X636842Y-283991D01*
X638371Y-285158D01*
X639681Y-286907D01*
X640555Y-288949D01*
X640991Y-291282D01*
Y-293616D01*
X640555Y-295949D01*
X639681Y-297991D01*
X638371Y-299741D01*
X636842Y-300907D01*
X635096Y-301199D01*
G01X685937Y-283699D02*
X691396Y-301199D01*
X696855Y-283699D01*
G01X713263Y-301199D02*
X704529D01*
Y-283699D01*
X713263D01*
G01X709769Y-292157D02*
X704529D01*
G01X722029Y-301199D02*
Y-283699D01*
X727488D01*
X729234Y-284574D01*
X730326Y-285741D01*
X730763Y-288074D01*
X730326Y-290408D01*
X729016Y-291866D01*
X727488Y-292741D01*
X722029D01*
G01X727488D02*
X730763Y-301199D01*
G01X743896Y-301782D02*
X743459Y-301491D01*
Y-300907D01*
X743896Y-300616D01*
X744333Y-300907D01*
Y-301491D01*
X743896Y-301782D01*
G01X717646Y-346199D02*
Y-328699D01*
X715026Y-332199D01*
G01Y-346199D02*
X720266D01*
G01X823846Y-328699D02*
Y-346199D01*
G01X818824Y-328699D02*
X828868D01*
G01X835669Y-346199D02*
Y-328699D01*
X841346Y-343282D01*
X847023Y-328699D01*
Y-346199D01*
G01X853387D02*
X858846Y-328699D01*
X864305Y-346199D01*
G01X862339Y-340074D02*
X855352D01*
G01X871761Y-343866D02*
X873508Y-345324D01*
X875473Y-346199D01*
X877219D01*
X878966Y-345324D01*
X880276Y-343866D01*
X880931Y-341824D01*
X880494Y-339783D01*
X879403Y-338032D01*
X877438Y-336866D01*
X874818Y-336282D01*
X873289Y-335116D01*
X872634Y-333074D01*
X873071Y-331032D01*
X874163Y-329574D01*
X875691Y-328699D01*
X877219D01*
X878748Y-329282D01*
X880058Y-330741D01*
G01X889043Y-346199D02*
Y-328699D01*
G01X897339D02*
X889043Y-339491D01*
G01X898649Y-346199D02*
X892754Y-334533D01*
G01X819479Y-283699D02*
Y-301199D01*
X828213D01*
G01X845276D02*
Y-289533D01*
G01Y-291574D02*
X844403Y-290408D01*
X843092Y-289824D01*
X841564Y-289533D01*
X840036Y-290116D01*
X838726Y-291282D01*
X837852Y-293032D01*
X837416Y-295366D01*
X837852Y-297699D01*
X838726Y-299449D01*
X840036Y-300616D01*
X841564Y-301199D01*
X843092Y-300907D01*
X844403Y-300033D01*
X845276Y-298866D01*
G01X854261Y-306449D02*
X855571Y-307032D01*
X857318Y-306449D01*
X858409Y-305283D01*
X859283Y-303824D01*
X860592Y-299158D01*
X863431Y-289533D01*
G01X856444D02*
X860592Y-299158D01*
G01X873071Y-293324D02*
X880058D01*
X879403Y-291282D01*
X878311Y-290116D01*
X876783Y-289533D01*
X875254Y-289824D01*
X873944Y-290699D01*
X873071Y-292741D01*
X872634Y-294491D01*
Y-296241D01*
X873071Y-297991D01*
X874163Y-299741D01*
X875473Y-300907D01*
X877001Y-301199D01*
X878529Y-300616D01*
X880058Y-298866D01*
G01X890789Y-301199D02*
Y-289533D01*
G01Y-291866D02*
X891881Y-290699D01*
X892973Y-289824D01*
X894501Y-289533D01*
X895592Y-289824D01*
X896903Y-290699D01*
G01X959846Y-328699D02*
X962902Y-346199D01*
X966396Y-328699D01*
X969889Y-346199D01*
X972946Y-328699D01*
G01X979529Y-346199D02*
Y-328699D01*
X984769D01*
X986516Y-329574D01*
X987826Y-331616D01*
X988263Y-333949D01*
X987826Y-336282D01*
X986734Y-338032D01*
X984769Y-338908D01*
X979529D01*
G01X996811Y-346199D02*
Y-328699D01*
G01X1005981D02*
Y-346199D01*
G01Y-337449D02*
X996811D01*
G01X1016058Y-340366D02*
X1021734D01*
G01X1031593Y-346199D02*
Y-328699D01*
G01X1039889D02*
X1031593Y-339491D01*
G01X1041199Y-346199D02*
X1035304Y-334533D01*
G01X1058263Y-346199D02*
X1049529D01*
Y-328699D01*
X1058263D01*
G01X1054769Y-337157D02*
X1049529D01*
G01X1066374Y-346199D02*
Y-328699D01*
X1076418Y-346199D01*
Y-328699D01*
G01X1083874Y-346199D02*
Y-328699D01*
X1093918Y-346199D01*
Y-328699D01*
G01X961593Y-301199D02*
Y-283699D01*
X965959D01*
X967706Y-284574D01*
X969016Y-285741D01*
X970108Y-287490D01*
X970981Y-289533D01*
X971199Y-292449D01*
X970981Y-295366D01*
X970108Y-297408D01*
X969016Y-299158D01*
X967706Y-300324D01*
X965959Y-301199D01*
X961593D01*
G01X980621Y-293324D02*
X987608D01*
X986953Y-291282D01*
X985861Y-290116D01*
X984333Y-289533D01*
X982804Y-289824D01*
X981494Y-290699D01*
X980621Y-292741D01*
X980184Y-294491D01*
Y-296241D01*
X980621Y-297991D01*
X981713Y-299741D01*
X983023Y-300907D01*
X984551Y-301199D01*
X986079Y-300616D01*
X987608Y-298866D01*
G01X998121Y-299158D02*
X999213Y-300324D01*
X1000741Y-301199D01*
X1002051D01*
X1003361Y-300616D01*
X1004234Y-299741D01*
X1004671Y-298575D01*
X1004453Y-296824D01*
X1003579Y-295949D01*
X999649Y-294199D01*
X998776Y-292157D01*
X999213Y-290699D01*
X1000086Y-289824D01*
X1001396Y-289533D01*
X1002706Y-289824D01*
X1004016Y-290699D01*
G01X1018896Y-289533D02*
Y-301199D01*
G01Y-284866D02*
X1018459Y-284574D01*
Y-283991D01*
X1018896Y-283699D01*
X1019333Y-283991D01*
Y-284574D01*
X1018896Y-284866D01*
G01X1033339Y-305574D02*
X1034868Y-306741D01*
X1036614Y-307032D01*
X1038142Y-306741D01*
X1039453Y-305283D01*
X1040326Y-303241D01*
Y-289533D01*
G01Y-291866D02*
X1039453Y-290699D01*
X1038142Y-289824D01*
X1036614Y-289533D01*
X1034868Y-290116D01*
X1033776Y-291282D01*
X1032902Y-293324D01*
X1032466Y-295366D01*
X1032684Y-297116D01*
X1033558Y-299158D01*
X1034868Y-300616D01*
X1036614Y-301199D01*
X1037924Y-300907D01*
X1039453Y-299741D01*
X1040326Y-298575D01*
G01X1050184Y-301199D02*
Y-289533D01*
G01Y-292449D02*
X1051058Y-290991D01*
X1052368Y-289824D01*
X1054114Y-289533D01*
X1055642Y-289824D01*
X1056953Y-290991D01*
X1057608Y-293032D01*
Y-301199D01*
G01X1068121Y-293324D02*
X1075108D01*
X1074453Y-291282D01*
X1073361Y-290116D01*
X1071833Y-289533D01*
X1070304Y-289824D01*
X1068994Y-290699D01*
X1068121Y-292741D01*
X1067684Y-294491D01*
Y-296241D01*
X1068121Y-297991D01*
X1069213Y-299741D01*
X1070523Y-300907D01*
X1072051Y-301199D01*
X1073579Y-300616D01*
X1075108Y-298866D01*
G01X1085839Y-301199D02*
Y-289533D01*
G01Y-291866D02*
X1086931Y-290699D01*
X1088023Y-289824D01*
X1089551Y-289533D01*
X1090642Y-289824D01*
X1091953Y-290699D01*
G01X1132596Y-346199D02*
Y-328699D01*
X1129976Y-332199D01*
G01Y-346199D02*
X1135216D01*
G01X1150096D02*
Y-328699D01*
X1147476Y-332199D01*
G01Y-346199D02*
X1152716D01*
G01X1163666Y-346782D02*
X1171526Y-328699D01*
G01X1185096Y-346199D02*
Y-328699D01*
X1182476Y-332199D01*
G01Y-346199D02*
X1187716D01*
G01X1198448Y-338908D02*
X1199976Y-336866D01*
X1201286Y-335699D01*
X1203033Y-335116D01*
X1204561Y-335699D01*
X1205653Y-336866D01*
X1206526Y-338616D01*
X1206744Y-340657D01*
X1206526Y-342408D01*
X1205653Y-344158D01*
X1204342Y-345616D01*
X1202814Y-346199D01*
X1201068Y-345616D01*
X1199539Y-343866D01*
X1198666Y-341241D01*
X1198448Y-338324D01*
X1198884Y-334533D01*
X1199539Y-332490D01*
X1200631Y-330449D01*
X1202159Y-328991D01*
X1203688Y-328699D01*
X1205216Y-329282D01*
X1206308Y-330741D01*
G01X1216166Y-346782D02*
X1224026Y-328699D01*
G01X1233448Y-331616D02*
X1234758Y-329866D01*
X1236286Y-328991D01*
X1238033Y-328699D01*
X1240216Y-329282D01*
X1241744Y-330741D01*
X1242181Y-332490D01*
X1241963Y-334241D01*
X1241089Y-335699D01*
X1236723Y-338616D01*
X1234758Y-340657D01*
X1233448Y-343575D01*
X1233011Y-346199D01*
X1242181D01*
G01X1255096Y-328699D02*
X1253349Y-329282D01*
X1252039Y-330741D01*
X1251166Y-332490D01*
X1250511Y-334824D01*
X1250293Y-337449D01*
X1250511Y-340074D01*
X1251166Y-342408D01*
X1252039Y-344158D01*
X1253349Y-345616D01*
X1255096Y-346199D01*
X1256842Y-345616D01*
X1258153Y-344158D01*
X1259026Y-342408D01*
X1259681Y-340074D01*
X1259899Y-337449D01*
X1259681Y-334824D01*
X1259026Y-332490D01*
X1258153Y-330741D01*
X1256842Y-329282D01*
X1255096Y-328699D01*
G01X1272596Y-346199D02*
Y-328699D01*
X1269976Y-332199D01*
G01Y-346199D02*
X1275216D01*
G01X1285948Y-338908D02*
X1287476Y-336866D01*
X1288786Y-335699D01*
X1290533Y-335116D01*
X1292061Y-335699D01*
X1293153Y-336866D01*
X1294026Y-338616D01*
X1294244Y-340657D01*
X1294026Y-342408D01*
X1293153Y-344158D01*
X1291842Y-345616D01*
X1290314Y-346199D01*
X1288568Y-345616D01*
X1287039Y-343866D01*
X1286166Y-341241D01*
X1285948Y-338324D01*
X1286384Y-334533D01*
X1287039Y-332490D01*
X1288131Y-330449D01*
X1289659Y-328991D01*
X1291188Y-328699D01*
X1292716Y-329282D01*
X1293808Y-330741D01*
G01X1180293Y-301199D02*
Y-283699D01*
X1184659D01*
X1186406Y-284574D01*
X1187716Y-285741D01*
X1188808Y-287490D01*
X1189681Y-289533D01*
X1189899Y-292449D01*
X1189681Y-295366D01*
X1188808Y-297408D01*
X1187716Y-299158D01*
X1186406Y-300324D01*
X1184659Y-301199D01*
X1180293D01*
G01X1206526D02*
Y-289533D01*
G01Y-291574D02*
X1205653Y-290408D01*
X1204342Y-289824D01*
X1202814Y-289533D01*
X1201286Y-290116D01*
X1199976Y-291282D01*
X1199102Y-293032D01*
X1198666Y-295366D01*
X1199102Y-297699D01*
X1199976Y-299449D01*
X1201286Y-300616D01*
X1202814Y-301199D01*
X1204342Y-300907D01*
X1205653Y-300033D01*
X1206526Y-298866D01*
G01X1220096Y-283699D02*
Y-301199D01*
G01X1217039Y-289533D02*
X1223153D01*
G01X1234321Y-293324D02*
X1241308D01*
X1240653Y-291282D01*
X1239561Y-290116D01*
X1238033Y-289533D01*
X1236504Y-289824D01*
X1235194Y-290699D01*
X1234321Y-292741D01*
X1233884Y-294491D01*
Y-296241D01*
X1234321Y-297991D01*
X1235413Y-299741D01*
X1236723Y-300907D01*
X1238251Y-301199D01*
X1239779Y-300616D01*
X1241308Y-298866D01*
G54D40*
X31600Y204900D03*
X46950Y200100D03*
X52700Y775300D03*
X82350Y199400D03*
X67800Y204800D03*
X85650Y702150D03*
X161400Y727900D03*
Y748900D03*
X154200Y783000D03*
Y804000D03*
X193700Y704000D03*
Y725000D03*
Y759500D03*
Y780500D03*
X208200Y530000D03*
X286200Y126000D03*
X282900Y630200D03*
X305039Y340501D03*
X306700Y712400D03*
X470400Y367800D03*
Y388800D03*
X523900Y829700D03*
X646100Y814500D03*
X727909Y68898D03*
X708224D03*
X747594D03*
X846134Y-1815D03*
X1169900Y814200D03*
X1296806Y7874D03*
Y31496D03*
Y55118D03*
Y78740D03*
X1299000Y818400D03*
X1341200Y246500D03*
G54D106*
X259500Y134250D03*
X1337000Y282750D03*
G54D133*
X597522Y356988D03*
Y366212D03*
X603478D03*
Y356988D03*
G54D13*
X22000Y174800D03*
X48400Y272800D03*
X38500Y284400D03*
X47300Y713200D03*
X72300Y265500D03*
X95223Y392504D03*
X68500Y424300D03*
X74000Y564800D03*
X80500Y566300D03*
X84000D03*
X98500Y601800D03*
X81000Y585800D03*
X81500Y637800D03*
X74600Y731100D03*
X104050Y135260D03*
X100900Y181400D03*
X121799Y363564D03*
X108400Y392000D03*
X118351Y578236D03*
X113851D03*
X145809Y578430D03*
X152319Y578520D03*
X159751Y578436D03*
X153700Y736200D03*
X150200D03*
X146500Y791300D03*
X143000D03*
X186000Y712300D03*
X182500D03*
X186000Y767800D03*
X182500D03*
X205200Y199900D03*
X213500Y513800D03*
X209500D03*
X221000Y521800D03*
X246500Y529300D03*
X282300Y503000D03*
X459200Y376100D03*
X462700D03*
X515950Y133860D03*
X519450D03*
X524450D03*
X527950D03*
X532950D03*
X536450D03*
X525409Y324341D03*
X541450Y133860D03*
X544950D03*
X554400Y342900D03*
X600800Y133700D03*
X588000Y133800D03*
X584500D03*
X577730Y133780D03*
X574300D03*
X593000Y133800D03*
X596500D03*
X604300Y133700D03*
X638000Y133800D03*
X634500D03*
X627676D03*
X624176D03*
X609500Y367913D03*
X646000Y133800D03*
X642500D03*
X861752Y17800D03*
X858252D03*
X854500Y49300D03*
X878800Y56400D03*
X1043418Y35766D03*
X1142000Y133800D03*
X1138500D03*
X1161407Y134454D03*
X1157907D03*
X1199500Y133800D03*
X1196000D03*
X1190935Y133848D03*
X1207949Y133730D03*
X1204449D03*
X1187435Y133848D03*
X1178661Y133927D03*
X1182161D03*
X1243000Y133800D03*
X1239500D03*
X1234309Y133912D03*
X1230809D03*
X1225448Y133909D03*
X1221948D03*
X1277365Y133622D03*
X1273865D03*
X1258544Y133719D03*
X1262044D03*
X1296117Y133427D03*
X1292617D03*
X1286643Y133530D03*
X1283143D03*
X1319000Y282300D03*
X1378160Y184601D03*
G54D22*
X28000Y321200D03*
X43300Y394400D03*
X64700Y417000D03*
X87230Y273800D03*
X87685Y489504D03*
Y486004D03*
X75700Y719300D03*
X100800Y306700D03*
X108751Y638436D03*
X124100Y714300D03*
Y710800D03*
X143269Y640420D03*
X143251Y648436D03*
X133751Y643936D03*
X143251D03*
X177821Y598436D03*
X277700Y122000D03*
X274500Y634900D03*
X325292Y295900D03*
X315700Y534500D03*
X619763Y213608D03*
X887600Y51500D03*
X904700Y45000D03*
Y48500D03*
X941981Y25374D03*
X1019063Y17398D03*
X1076700Y57000D03*
Y60500D03*
Y53500D03*
Y50000D03*
X1126100Y129800D03*
Y133300D03*
X1317200Y286500D03*
G54D31*
X24050Y691400D03*
X31550Y687525D03*
Y695275D03*
X43950Y690300D03*
X51450Y686425D03*
Y694175D03*
X152435Y331811D03*
X159935Y327936D03*
Y335686D03*
X137167Y333265D03*
X144667Y337140D03*
Y329390D03*
X213607Y130425D03*
X206107Y134300D03*
X213607Y138175D03*
X739750Y44500D03*
X747250Y40625D03*
X762250D03*
X747250Y48375D03*
X754750Y44500D03*
X762250Y48375D03*
X824450Y60025D03*
X816950Y63900D03*
X824450Y67775D03*
X935350Y67400D03*
X942850Y63525D03*
Y71275D03*
G54D124*
X533010Y69803D03*
X530057Y67048D03*
X535962Y64292D03*
X524151Y69803D03*
X527104Y64292D03*
X535962Y49331D03*
X527104D03*
X530057Y52087D03*
X533010Y54843D03*
X524151D03*
X533010Y99725D03*
X530057Y96969D03*
X535962Y94213D03*
X524151Y99725D03*
X527104Y94213D03*
X533010Y84764D03*
X530057Y82008D03*
X535962Y79252D03*
X524151Y84764D03*
X527104Y79252D03*
X567458Y54843D03*
X570411Y49331D03*
Y64292D03*
X567458Y69803D03*
X541868D03*
X538915Y67048D03*
X547773D03*
X544821Y64292D03*
Y49331D03*
X547773Y52087D03*
X538915D03*
X541868Y54843D03*
X570411Y79252D03*
Y94213D03*
X567458Y84764D03*
Y99725D03*
X541868D03*
X538915Y96969D03*
X547773D03*
X544821Y94213D03*
X541868Y84764D03*
X538915Y82008D03*
X547773D03*
X544821Y79252D03*
X576317Y54843D03*
X585175D03*
X573364Y52087D03*
X582222D03*
X591080D03*
X579269Y49331D03*
X588128D03*
X576317Y69803D03*
X585175D03*
X573364Y67048D03*
X582222D03*
X591080D03*
X579269Y64292D03*
X588128D03*
X579269Y79252D03*
X588128D03*
X582222Y82008D03*
X591080D03*
X585175Y84764D03*
X576317D03*
X573364Y82008D03*
X576317Y99725D03*
X585175D03*
X573364Y96969D03*
X582222D03*
X579269Y94213D03*
X588128D03*
X591080Y96969D03*
X619624Y54843D03*
X628482D03*
X616671Y52087D03*
X625529D03*
X634388D03*
X622577Y49331D03*
X631435D03*
X619624Y69803D03*
X628482D03*
X616671Y67048D03*
X625529D03*
X634388D03*
X622577Y64292D03*
X631435D03*
X610766Y54843D03*
X613718Y49331D03*
Y64292D03*
X610766Y69803D03*
X622577Y79252D03*
X631435D03*
X625529Y82008D03*
X634388D03*
X628482Y84764D03*
X619624D03*
X616671Y82008D03*
X619624Y99725D03*
X628482D03*
X616671Y96969D03*
X625529D03*
X622577Y94213D03*
X631435D03*
X634388Y96969D03*
X613718Y79252D03*
Y94213D03*
X610766Y84764D03*
Y99725D03*
X662931Y54843D03*
X671789D03*
X659978Y52087D03*
X668836D03*
X665884Y49331D03*
X662931Y69803D03*
X671789D03*
X659978Y67048D03*
X668836D03*
X665884Y64292D03*
X654073Y54843D03*
X657025Y49331D03*
Y64292D03*
X654073Y69803D03*
X665884Y79252D03*
X668836Y82008D03*
X671789Y84764D03*
X662931D03*
X659978Y82008D03*
X662931Y99725D03*
X671789D03*
X659978Y96969D03*
X668836D03*
X665884Y94213D03*
X657025Y79252D03*
Y94213D03*
X654073Y84764D03*
Y99725D03*
X677695Y52087D03*
X674742Y49331D03*
X677695Y67048D03*
X674742Y64292D03*
Y79252D03*
X677695Y82008D03*
X674742Y94213D03*
X677695Y96969D03*
X1135372Y69803D03*
X1144230D03*
X1132419Y67048D03*
X1141277D03*
X1138324Y64292D03*
X1126513Y69803D03*
X1129466Y64292D03*
X1138324Y49331D03*
X1129466D03*
X1141277Y52087D03*
X1132419D03*
X1144230Y54843D03*
X1135372D03*
X1126513D03*
X1135372Y99725D03*
X1144230D03*
X1132419Y96969D03*
X1141277D03*
X1138324Y94213D03*
X1126513Y99725D03*
X1129466Y94213D03*
X1135372Y84764D03*
X1144230D03*
X1132419Y82008D03*
X1141277D03*
X1138324Y79252D03*
X1126513Y84764D03*
X1129466Y79252D03*
X1178679Y54843D03*
X1175726Y52087D03*
X1178679Y69803D03*
X1175726Y67048D03*
X1169820Y54843D03*
X1172773Y49331D03*
Y64292D03*
X1169820Y69803D03*
X1150135Y67048D03*
X1147183Y64292D03*
Y49331D03*
X1150135Y52087D03*
X1178679Y84764D03*
X1175726Y82008D03*
X1178679Y99725D03*
X1175726Y96969D03*
X1172773Y79252D03*
Y94213D03*
X1169820Y84764D03*
Y99725D03*
X1150135Y96969D03*
X1147183Y94213D03*
X1150135Y82008D03*
X1147183Y79252D03*
X1187537Y54843D03*
X1184584Y52087D03*
X1193442D03*
X1181631Y49331D03*
X1190490D03*
X1187537Y69803D03*
X1184584Y67048D03*
X1193442D03*
X1181631Y64292D03*
X1190490D03*
X1181631Y79252D03*
X1190490D03*
X1184584Y82008D03*
X1193442D03*
X1187537Y84764D03*
Y99725D03*
X1184584Y96969D03*
X1181631Y94213D03*
X1190490D03*
X1193442Y96969D03*
X1221986Y54843D03*
X1230844D03*
X1219033Y52087D03*
X1227891D03*
X1236750D03*
X1224939Y49331D03*
X1233797D03*
X1221986Y69803D03*
X1230844D03*
X1219033Y67048D03*
X1227891D03*
X1236750D03*
X1224939Y64292D03*
X1233797D03*
X1213128Y54843D03*
X1216080Y49331D03*
Y64292D03*
X1213128Y69803D03*
X1224939Y79252D03*
X1233797D03*
X1227891Y82008D03*
X1236750D03*
X1230844Y84764D03*
X1221986D03*
X1219033Y82008D03*
X1221986Y99725D03*
X1230844D03*
X1219033Y96969D03*
X1227891D03*
X1224939Y94213D03*
X1233797D03*
X1236750Y96969D03*
X1216080Y79252D03*
Y94213D03*
X1213128Y84764D03*
Y99725D03*
X1265293Y54843D03*
X1274151D03*
X1262340Y52087D03*
X1271198D03*
X1280057D03*
X1268246Y49331D03*
X1277104D03*
X1265293Y69803D03*
X1274151D03*
X1262340Y67048D03*
X1271198D03*
X1280057D03*
X1268246Y64292D03*
X1277104D03*
X1256435Y54843D03*
X1259387Y49331D03*
Y64292D03*
X1256435Y69803D03*
X1268246Y79252D03*
X1277104D03*
X1271198Y82008D03*
X1280057D03*
X1274151Y84764D03*
X1265293D03*
X1262340Y82008D03*
X1265293Y99725D03*
X1274151D03*
X1262340Y96969D03*
X1271198D03*
X1268246Y94213D03*
X1277104D03*
X1280057Y96969D03*
X1259387Y79252D03*
Y94213D03*
X1256435Y84764D03*
Y99725D03*
G54D151*
X1027722Y-9125D03*
X1054494D03*
G54D142*
X783300Y1100D03*
X794900D03*
X838300Y2000D03*
X826700D03*
G54D115*
X272979Y354640D03*
X291479D03*
G54D152*
X1024330Y26232D03*
X1028330Y35032D03*
X1020330D03*
G54D50*
X49866Y364307D03*
X44866D03*
X39866D03*
X34866D03*
Y384307D03*
X39866D03*
X44866D03*
X49866D03*
X191018Y211856D03*
X196018D03*
Y239356D03*
X191018D03*
X201018Y211856D03*
X206018D03*
Y239356D03*
X201018D03*
X236231Y245705D03*
X241231D03*
X246231D03*
X251231D03*
X256231D03*
X261231D03*
X266231D03*
Y282855D03*
X261231D03*
X256231D03*
X251231D03*
X246231D03*
X241231D03*
X236231D03*
X271231Y245705D03*
Y282855D03*
X302834Y245636D03*
X307834D03*
X312834D03*
X317834D03*
X322834D03*
X327834D03*
X332834D03*
Y282786D03*
X327834D03*
X322834D03*
X317834D03*
X312834D03*
X307834D03*
X302834D03*
X337834Y245636D03*
Y282786D03*
X519526Y251011D03*
X524526D03*
X529526D03*
X534526D03*
Y278511D03*
X529526D03*
X524526D03*
X519526D03*
G54D116*
X298306Y735298D03*
X295746D03*
X293186D03*
X290626D03*
X288066D03*
X285506D03*
X282946D03*
X280386D03*
X277826D03*
Y757498D03*
X280386D03*
X282946D03*
X285506D03*
X288066D03*
X290626D03*
X293186D03*
X295746D03*
X298306D03*
X305986Y735298D03*
X303426D03*
X300866D03*
Y757498D03*
X303426D03*
X305986D03*
X461440Y84600D03*
X464000D03*
X466560D03*
X469120D03*
Y106800D03*
X466560D03*
X464000D03*
X461440D03*
X471680Y84600D03*
X474240D03*
X476800D03*
X479360D03*
Y106800D03*
X476800D03*
X474240D03*
X471680D03*
X491326Y809498D03*
X493886D03*
X496446D03*
X499006D03*
X501566D03*
Y787298D03*
X499006D03*
X496446D03*
X493886D03*
X491326D03*
X504126Y809498D03*
X506686D03*
X509246D03*
X511806D03*
X514366D03*
X516926D03*
X519486D03*
Y787298D03*
X516926D03*
X514366D03*
X511806D03*
X509246D03*
X506686D03*
X504126D03*
X873626Y764298D03*
X871066D03*
X868506D03*
X865946D03*
X863386D03*
X860826D03*
Y786498D03*
X863386D03*
X865946D03*
X868506D03*
X871066D03*
X873626D03*
X891660Y334690D03*
X894220D03*
X896780D03*
X899340D03*
Y318510D03*
X896780D03*
X894220D03*
X891660D03*
X888986Y764298D03*
X886426D03*
X883866D03*
X881306D03*
X878746D03*
X876186D03*
Y786498D03*
X878746D03*
X881306D03*
X883866D03*
X886426D03*
X888986D03*
X1007253Y13707D03*
X1004753D03*
X1002253D03*
X999753D03*
X997253D03*
Y34307D03*
X999753D03*
X1002253D03*
X1004753D03*
X1007253D03*
X1014753Y13707D03*
X1012253D03*
X1009753D03*
Y34307D03*
X1012253D03*
X1014753D03*
X1264820Y377500D03*
X1267380D03*
X1269940D03*
X1272500D03*
X1275060D03*
X1277620D03*
Y355300D03*
X1275060D03*
X1272500D03*
X1269940D03*
X1267380D03*
X1264820D03*
X1280180Y377500D03*
X1282740D03*
X1285300D03*
X1287860D03*
X1290420D03*
X1292980D03*
Y355300D03*
X1290420D03*
X1287860D03*
X1285300D03*
X1282740D03*
X1280180D03*
X1305548Y714967D03*
X1308108D03*
X1310668D03*
Y692767D03*
X1308108D03*
X1305548D03*
X1313228Y714967D03*
X1315788D03*
X1318348D03*
X1320908D03*
X1323468D03*
X1326028D03*
X1328588D03*
X1331148D03*
X1333708D03*
Y692767D03*
X1331148D03*
X1328588D03*
X1326028D03*
X1323468D03*
X1320908D03*
X1318348D03*
X1315788D03*
X1313228D03*
G54D107*
X259500Y131750D03*
X1337000Y280250D03*
G54D23*
X27000Y362700D03*
X53000Y207900D03*
X57000D03*
X37650Y212700D03*
X41650D03*
X53422Y357814D03*
X53200Y477700D03*
X64000Y494200D03*
X46900Y493900D03*
X31200Y712600D03*
X57200Y686400D03*
X60800Y766500D03*
X56700D03*
X52300Y766600D03*
X35000Y766800D03*
X39000D03*
X92400Y207300D03*
X88400D03*
X92400Y218700D03*
X77800Y212800D03*
X73800Y224300D03*
X88400Y218700D03*
X73800Y212800D03*
X77800Y224300D03*
X76170Y262620D03*
X96043Y434143D03*
X72500Y424200D03*
X84900Y585700D03*
X66000Y594200D03*
X80950Y705350D03*
X91800Y723100D03*
X74300Y766100D03*
X108050Y135160D03*
X106500Y280600D03*
X108500Y290600D03*
X117761Y372506D03*
X104507Y392134D03*
X127400Y408300D03*
X120252Y443752D03*
X100079Y426717D03*
X116235Y451235D03*
X103500Y461200D03*
X115500D03*
X106900Y728000D03*
X162900Y240990D03*
X146000Y370700D03*
X155700Y409700D03*
X134571Y409796D03*
X135250Y443690D03*
X146200Y461200D03*
X150632Y453555D03*
X146431Y453478D03*
X138769Y578420D03*
X153700Y744100D03*
X164500Y778200D03*
X160000Y816200D03*
X146500Y799200D03*
X186418Y199756D03*
X185500Y574200D03*
X189500D03*
X195500Y601700D03*
X191500Y594200D03*
Y586700D03*
X199500Y737200D03*
X186000Y720200D03*
X184700Y736100D03*
X171700Y723100D03*
X186000Y775700D03*
X167200Y761100D03*
X199500Y792700D03*
X177500Y791200D03*
X225900Y105300D03*
X200300Y199800D03*
X225000Y529200D03*
X229000Y521800D03*
X205500Y574200D03*
X204000Y699200D03*
X217000Y712200D03*
X204000Y754700D03*
X217000Y767700D03*
X240400Y233800D03*
X266729Y357340D03*
X260600Y476500D03*
X242500Y521200D03*
X257500Y529200D03*
X253500Y521200D03*
X237300Y639100D03*
X281500Y137200D03*
X281100Y208500D03*
X278100Y478000D03*
X284200Y474500D03*
X282500Y495200D03*
X274406Y723098D03*
X278406D03*
X286500Y779700D03*
X291000Y772100D03*
X295079Y772050D03*
X299148Y772305D03*
X286500Y772200D03*
X308300Y336000D03*
X301929Y358440D03*
X304000Y779900D03*
X307406Y772098D03*
X311406D03*
X315406D03*
X303300Y772000D03*
X337410Y295860D03*
X461900Y68900D03*
X455800Y98900D03*
Y106400D03*
X466905Y122328D03*
X462868Y122324D03*
X462700Y384000D03*
X470200Y68900D03*
X478400D03*
X480881Y140014D03*
X498903Y168592D03*
X498400Y201900D03*
X480700Y363000D03*
X493700Y376000D03*
X476200Y401000D03*
X487906Y775098D03*
X491906D03*
X500100Y824100D03*
X507700Y171500D03*
X507300Y182400D03*
X531232Y236924D03*
X522899Y236937D03*
X517599D03*
X527131Y236880D03*
X535295Y236958D03*
X524177Y294640D03*
X532921Y294517D03*
X536953Y294760D03*
X520906Y824098D03*
X504406D03*
X524906D03*
X508500Y824100D03*
X512579Y824050D03*
X528906Y824098D03*
X516679Y824050D03*
X532906Y824098D03*
X565690Y133430D03*
X569700D03*
X550400Y165000D03*
X567200Y164700D03*
X554500Y165000D03*
X563100Y164700D03*
X542490Y163801D03*
X575600Y164600D03*
X571400Y164700D03*
X613709Y133281D03*
X617711D03*
X627363Y231808D03*
X628000Y337300D03*
X624000D03*
X632000Y324300D03*
X615100Y365200D03*
X613500Y357083D03*
X632000Y379300D03*
X627500D03*
X636300D03*
X617000Y390300D03*
X627500Y387300D03*
X623000Y390300D03*
X640500Y379300D03*
X724890Y59830D03*
X765300Y107600D03*
X791800Y29300D03*
X781100Y138600D03*
X815500Y20500D03*
X820018Y51079D03*
X824118D03*
X850300Y17700D03*
X867500Y23700D03*
Y16200D03*
X857406Y752098D03*
X861406D03*
X869756Y801098D03*
X873850Y801100D03*
X870900Y808800D03*
X896500Y16700D03*
X886520Y16702D03*
X899200Y65100D03*
X906500Y93200D03*
X893000D03*
X897500D03*
X884000D03*
X879500D03*
X902000D03*
X888500D03*
X875000D03*
X895000Y309300D03*
X891000D03*
X886276Y803748D03*
X890406Y801098D03*
X877949Y803700D03*
X894406Y801098D03*
X882049Y803700D03*
X898406Y801098D03*
X955400Y72400D03*
X951500Y93200D03*
X947000D03*
X942500D03*
X996230Y46444D03*
X1033000Y69700D03*
X1037000Y105200D03*
X1041500D03*
X1024000D03*
X1028000D03*
X1032500D03*
X1020000D03*
X1015948D03*
X1068673Y24345D03*
X1070733Y44623D03*
X1050500Y105200D03*
X1046000D03*
X1173479Y133571D03*
X1169467Y133576D03*
X1216752Y133515D03*
X1212748D03*
X1270005Y133621D03*
X1265997Y133622D03*
X1258500Y342200D03*
X1270500D03*
X1262500D03*
X1266500D03*
X1277500Y401200D03*
Y393700D03*
X1307000Y282200D03*
X1301500Y393700D03*
X1293500D03*
X1297500D03*
X1285500D03*
X1305500D03*
X1289500D03*
X1302128Y680567D03*
X1306128D03*
X1335071Y137811D03*
X1317300Y301600D03*
X1321400D03*
X1315000Y282200D03*
X1313000Y293200D03*
X1314628Y729567D03*
X1326128D03*
X1330128D03*
X1334128D03*
X1338128D03*
X1326100Y737600D03*
X1361500Y270200D03*
G54D32*
X25100Y746900D03*
Y733400D03*
Y729400D03*
X42300Y276800D03*
Y280900D03*
X35700Y394100D03*
X55800Y483000D03*
Y502000D03*
X55400Y708900D03*
X53200Y770800D03*
X97800Y276300D03*
X67143Y354737D03*
X70800Y506500D03*
Y510500D03*
Y514500D03*
X81000Y529300D03*
X66940Y527270D03*
X80800Y542300D03*
Y546300D03*
X98300Y569500D03*
X80700Y550400D03*
X80800Y554500D03*
Y558500D03*
X98300Y592500D03*
X73800Y586000D03*
X86800Y642000D03*
Y646000D03*
X95000Y681900D03*
X78400Y731300D03*
Y727300D03*
X79600Y740900D03*
Y744900D03*
Y766900D03*
X100800Y298900D03*
Y302900D03*
X112300Y388600D03*
X112234Y441150D03*
X107300Y561500D03*
Y565500D03*
X102500Y681900D03*
X116200Y714300D03*
X99200Y727800D03*
X129000Y745200D03*
X118300Y775000D03*
X149614Y322277D03*
X142113Y322350D03*
X132814Y373985D03*
X157400Y379200D03*
X143298Y420306D03*
X137200Y732300D03*
X164300Y808500D03*
X169084Y186686D03*
Y181686D03*
X194000Y251100D03*
X190615Y289501D03*
X179154Y446672D03*
X171500Y753400D03*
X200560Y289306D03*
X210038Y425645D03*
X209838Y441945D03*
X206000Y446000D03*
X209800Y465000D03*
Y469000D03*
Y482000D03*
Y486000D03*
X209900Y494400D03*
X209800Y490000D03*
Y525500D03*
Y521500D03*
Y554500D03*
X222670Y568020D03*
X230300Y586000D03*
Y590000D03*
X203800Y729500D03*
Y785000D03*
X236300Y139500D03*
X250528Y124804D03*
X253200Y438600D03*
X255900Y422500D03*
X250000Y443300D03*
X252320Y581381D03*
X269800Y126000D03*
X269400Y467300D03*
Y485800D03*
X274600Y638900D03*
X282100Y643900D03*
X311300Y221900D03*
X315700Y542500D03*
X335200Y222000D03*
X334900Y335500D03*
X344600Y318500D03*
X460149Y210989D03*
X496832Y130548D03*
X480809Y339041D03*
Y334041D03*
X480500Y393300D03*
X526600Y165815D03*
Y157715D03*
Y161815D03*
X515709Y202072D03*
X508009Y202172D03*
X522400Y340500D03*
X558270Y136909D03*
X550800Y137597D03*
X558331Y334980D03*
X589763Y215308D03*
X572400Y238400D03*
X619663Y217608D03*
X612163Y213608D03*
X605000Y344200D03*
X663800Y212000D03*
X689200Y212200D03*
X677800Y212000D03*
X722513Y2380D03*
X733063Y31882D03*
X717305Y14964D03*
X720959Y28613D03*
X734930Y63910D03*
X714300Y64000D03*
X713410Y55860D03*
Y51796D03*
X752600Y53800D03*
X757750Y75900D03*
X757900Y86500D03*
Y90600D03*
Y102900D03*
Y82300D03*
X765500Y121200D03*
Y133500D03*
X755800Y118800D03*
X774900Y74000D03*
X794900Y74200D03*
X806800Y86500D03*
Y90600D03*
X835400Y105600D03*
X808713Y118898D03*
X846181Y5499D03*
X861800Y32000D03*
Y40000D03*
X862300Y52800D03*
Y48500D03*
X904800Y37000D03*
X900300Y358500D03*
Y350000D03*
Y345600D03*
X886470Y808230D03*
X928900Y78600D03*
X955381Y64624D03*
X989011Y14160D03*
X989169Y27248D03*
Y23121D03*
X1021360Y2024D03*
X1033416Y33563D03*
X1032192Y11076D03*
X1039967Y11296D03*
X1075859Y5500D03*
Y500D03*
X1051300Y22200D03*
X1075869Y22450D03*
X1076424Y39554D03*
X1075869Y26950D03*
X1076424Y35054D03*
X1075139Y14070D03*
X1054800Y48700D03*
X1049400Y64100D03*
X1120300Y235000D03*
X1134300Y234500D03*
X1148800D03*
X1289300Y300000D03*
X1315300Y274500D03*
X1356800Y278500D03*
G54D143*
X803264Y0D03*
X815634D03*
G54D14*
X26977Y151614D03*
X96189D03*
G54D134*
X624934Y257608D03*
X656592D03*
G54D125*
X530152Y175634D03*
X522278D03*
X530152Y192366D03*
X522278D03*
X569522Y175634D03*
X561648D03*
X553774D03*
X545900D03*
X538026D03*
X569522Y192366D03*
X561648D03*
X553774D03*
X545900D03*
X538026D03*
G54D41*
X37200Y204900D03*
X52550Y200100D03*
X58300Y775300D03*
X87950Y199400D03*
X73400Y204800D03*
X91250Y702150D03*
X159800Y783000D03*
Y804000D03*
X199300Y704000D03*
Y725000D03*
X167000Y727900D03*
Y748900D03*
X199300Y759500D03*
Y780500D03*
X213800Y530000D03*
X291800Y126000D03*
X288500Y630200D03*
X310639Y340501D03*
X312300Y712400D03*
X476000Y367800D03*
Y388800D03*
X529500Y829700D03*
X651700Y814500D03*
X733509Y68898D03*
X713824D03*
X753194D03*
X851734Y-1815D03*
X1175500Y814200D03*
X1302406Y7874D03*
Y31496D03*
Y55118D03*
Y78740D03*
X1304600Y818400D03*
X1346800Y246500D03*
G54D15*
X21900Y195900D03*
X21800Y184400D03*
X23100Y220500D03*
X31500D03*
X38500Y276800D03*
X41500Y265300D03*
X43900Y303500D03*
X54600Y325200D03*
X61799Y376157D03*
X42900Y766800D03*
X67600Y330900D03*
X84700Y331800D03*
X81300D03*
X74000Y575800D03*
X84000Y574300D03*
X80500D03*
X100900Y194200D03*
X130051Y651946D03*
X133299Y578520D03*
X190520Y838101D03*
X194520D03*
X222500Y513800D03*
X226000D03*
X221000Y529300D03*
X207118Y838101D03*
X203118D03*
X219717D03*
X215717D03*
X232315D03*
X228315D03*
X239600Y149700D03*
X244300Y233800D03*
X246500Y521300D03*
X259857Y513748D03*
X241300Y639200D03*
X266906Y772198D03*
X254362Y838101D03*
X250362D03*
X266961D03*
X262961D03*
X267300Y296800D03*
X297729Y358440D03*
X279559Y838101D03*
X275559D03*
X329241Y328730D03*
X301500Y487100D03*
X313354Y838101D03*
X317354D03*
X329953D03*
X325953D03*
X367748D03*
X363748D03*
X342551D03*
X338551D03*
X351150D03*
X355150D03*
X389796D03*
X385796D03*
X398394D03*
X402394D03*
X410993D03*
X414993D03*
X423591D03*
X427591D03*
X459071Y122341D03*
X480406Y824198D03*
X505477Y295540D03*
X525409Y332341D03*
X542120Y218605D03*
X544851Y838101D03*
X548851D03*
X557449D03*
X561449D03*
X570048D03*
X604170Y334140D03*
X574048Y838101D03*
X586646D03*
X582646D03*
X599245D03*
X595245D03*
X619363Y231908D03*
X609500Y357183D03*
X611843Y838101D03*
X607843D03*
X624442D03*
X620442D03*
X637040D03*
X633040D03*
X659087D03*
X655087D03*
X671685D03*
X667685D03*
X684284D03*
X680284D03*
X696882D03*
X692882D03*
X724379D03*
X728379D03*
X736977D03*
X740977D03*
X749576D03*
X753576D03*
X762174D03*
X766174D03*
X774772D03*
X778772D03*
X787370D03*
X791370D03*
X799969D03*
X803969D03*
X812567D03*
X816567D03*
X837764D03*
X849906Y801198D03*
X841764Y838101D03*
X850362D03*
X854362D03*
X896000Y6300D03*
X900522Y16766D03*
X905500Y334800D03*
X1039675Y18887D03*
X1014451Y45106D03*
X1040914Y838101D03*
X1044914D03*
X1053512D03*
X1057512D03*
X1066111D03*
X1070111D03*
X1091307D03*
X1095307D03*
X1103906D03*
X1107906D03*
X1078709D03*
X1082709D03*
X1120504D03*
X1116504D03*
X1129103D03*
X1133103D03*
X1141701D03*
X1145701D03*
X1154299D03*
X1158299D03*
X1176347D03*
X1180347D03*
X1192945D03*
X1188945D03*
X1224441D03*
X1220441D03*
X1237040D03*
X1233040D03*
X1257500Y393800D03*
X1254000D03*
X1249638Y838101D03*
X1245638D03*
X1258237D03*
X1262237D03*
X1274835D03*
X1270835D03*
X1294628Y729667D03*
X1287433Y838101D03*
X1283433D03*
X1312630D03*
X1308630D03*
X1325229D03*
X1321229D03*
X1337827D03*
X1333827D03*
X1346425D03*
X1350425D03*
G54D117*
X320500Y165100D03*
Y189900D03*
X674763Y227208D03*
Y252008D03*
X674837Y266292D03*
Y291092D03*
X1234500Y202100D03*
Y226900D03*
Y260100D03*
Y284900D03*
X1255000Y202100D03*
Y226900D03*
Y260100D03*
Y284900D03*
G54D153*
X1056650Y36200D03*
X1049150D03*
X1056650Y28600D03*
G54D135*
X626110Y366593D03*
Y346607D03*
X639890D03*
Y366593D03*
G54D108*
X249857Y142157D03*
Y144126D03*
Y146094D03*
Y148063D03*
Y150031D03*
Y152000D03*
Y153969D03*
Y155937D03*
Y157906D03*
Y159874D03*
Y161843D03*
X269143D03*
Y159874D03*
Y157906D03*
Y155937D03*
Y153969D03*
Y152000D03*
Y150031D03*
Y148063D03*
Y146094D03*
Y144126D03*
Y142157D03*
X593120Y231015D03*
Y232984D03*
Y234952D03*
Y236921D03*
Y238889D03*
Y240858D03*
Y242827D03*
Y244795D03*
Y246764D03*
Y248732D03*
Y250701D03*
X612406Y242827D03*
Y240858D03*
Y238889D03*
Y236921D03*
Y234952D03*
Y232984D03*
Y231015D03*
Y250701D03*
Y248732D03*
Y246764D03*
Y244795D03*
X1346643Y273093D03*
Y271124D03*
Y269156D03*
Y267187D03*
Y265219D03*
Y263250D03*
Y261281D03*
Y259313D03*
Y257344D03*
Y255376D03*
Y253407D03*
X1327357D03*
Y255376D03*
Y257344D03*
Y259313D03*
Y261281D03*
Y263250D03*
Y265219D03*
Y267187D03*
Y269156D03*
Y271124D03*
Y273093D03*
G54D60*
X59221Y725150D03*
X57253D03*
X55284D03*
X53316D03*
X51347D03*
X49379D03*
Y744650D03*
X51347D03*
X53316D03*
X55284D03*
X57253D03*
X59221D03*
G54D51*
X59550Y367033D03*
Y358033D03*
X78500Y615500D03*
X70000D03*
X78500Y624500D03*
X70000D03*
G54D24*
X27000Y359300D03*
X37650Y209300D03*
X53000Y204500D03*
X41650Y209300D03*
X57000Y204500D03*
X53422Y354414D03*
X53200Y474300D03*
X64000Y490800D03*
X46900Y490500D03*
X31200Y709200D03*
X57200Y683000D03*
X60800Y763100D03*
X56700D03*
X52300Y763200D03*
X35000Y763400D03*
X39000D03*
X92400Y203900D03*
X88400D03*
X77800Y209400D03*
X73800D03*
X92400Y215300D03*
X73800Y220900D03*
X88400Y215300D03*
X77800Y220900D03*
X76170Y259220D03*
X96043Y430743D03*
X72500Y420800D03*
X84900Y582300D03*
X66000Y590800D03*
X80950Y701950D03*
X91800Y719700D03*
X74300Y762700D03*
X108050Y131760D03*
X106500Y277200D03*
X108500Y287200D03*
X117761Y369106D03*
X104507Y388734D03*
X127400Y404900D03*
X120252Y440352D03*
X100079Y423317D03*
X116235Y447835D03*
X103500Y457800D03*
X115500D03*
X106900Y724600D03*
X162900Y237590D03*
X146000Y367300D03*
X155700Y406300D03*
X134571Y406396D03*
X135250Y440290D03*
X146200Y457800D03*
X150632Y450155D03*
X146431Y450078D03*
X138769Y575020D03*
X153700Y740700D03*
X164500Y774800D03*
X160000Y812800D03*
X146500Y795800D03*
X186418Y196356D03*
X185500Y570800D03*
X189500D03*
X195500Y598300D03*
X191500Y590800D03*
Y583300D03*
X199500Y733800D03*
X186000Y716800D03*
X184700Y732700D03*
X171700Y719700D03*
X186000Y772300D03*
X167200Y757700D03*
X199500Y789300D03*
X177500Y787800D03*
X225900Y101900D03*
X200300Y196400D03*
X225000Y525800D03*
X229000Y518400D03*
X205500Y570800D03*
X204000Y695800D03*
X217000Y708800D03*
X204000Y751300D03*
X217000Y764300D03*
X240400Y230400D03*
X266729Y353940D03*
X260600Y473100D03*
X242500Y517800D03*
X257500Y525800D03*
X253500Y517800D03*
X237300Y635700D03*
X281500Y133800D03*
X281100Y205100D03*
X278100Y474600D03*
X284200Y471100D03*
X282500Y491800D03*
X274406Y719698D03*
X278406D03*
X286500Y776300D03*
X291000Y768700D03*
X295079Y768650D03*
X299148Y768905D03*
X286500Y768800D03*
X308300Y332600D03*
X301929Y355040D03*
X304000Y776500D03*
X307406Y768698D03*
X311406D03*
X315406D03*
X303300Y768600D03*
X337410Y292460D03*
X461900Y65500D03*
X455800Y95500D03*
Y103000D03*
X466905Y118928D03*
X462868Y118924D03*
X462700Y380600D03*
X470200Y65500D03*
X478400D03*
X480881Y136614D03*
X498903Y165192D03*
X498400Y198500D03*
X480700Y359600D03*
X493700Y372600D03*
X476200Y397600D03*
X487906Y771698D03*
X491906D03*
X500100Y820700D03*
X507700Y168100D03*
X507300Y179000D03*
X531232Y233524D03*
X522899Y233537D03*
X517599D03*
X527131Y233480D03*
X535295Y233558D03*
X524177Y291240D03*
X532921Y291117D03*
X536953Y291360D03*
X520906Y820698D03*
X504406D03*
X524906D03*
X508500Y820700D03*
X512579Y820650D03*
X528906Y820698D03*
X516679Y820650D03*
X532906Y820698D03*
X565690Y130030D03*
X569700D03*
X550400Y161600D03*
X567200Y161300D03*
X554500Y161600D03*
X563100Y161300D03*
X542490Y160401D03*
X575600Y161200D03*
X571400Y161300D03*
X613709Y129881D03*
X617711D03*
X627363Y228408D03*
X628000Y333900D03*
X624000D03*
X632000Y320900D03*
X615100Y361800D03*
X632000Y375900D03*
X613500Y353683D03*
X627500Y375900D03*
X636300D03*
X617000Y386900D03*
X627500Y383900D03*
X623000Y386900D03*
X640500Y375900D03*
X724890Y56430D03*
X765300Y104200D03*
X791800Y25900D03*
X781100Y135200D03*
X815500Y17100D03*
X820018Y47679D03*
X824118D03*
X850300Y14300D03*
X867500Y20300D03*
Y12800D03*
X857406Y748698D03*
X861406D03*
X869756Y797698D03*
X873850Y797700D03*
X870900Y805400D03*
X896500Y13300D03*
X886520Y13302D03*
X899200Y61700D03*
X906500Y89800D03*
X893000D03*
X897500D03*
X884000D03*
X879500D03*
X902000D03*
X888500D03*
X875000D03*
X895000Y305900D03*
X891000D03*
X886276Y800348D03*
X890406Y797698D03*
X877949Y800300D03*
X894406Y797698D03*
X882049Y800300D03*
X898406Y797698D03*
X955400Y69000D03*
X951500Y89800D03*
X947000D03*
X942500D03*
X996230Y43044D03*
X1033000Y66300D03*
X1037000Y101800D03*
X1041500D03*
X1024000D03*
X1028000D03*
X1032500D03*
X1020000D03*
X1015948D03*
X1070733Y41223D03*
X1068673Y20945D03*
X1050500Y101800D03*
X1046000D03*
X1173479Y130171D03*
X1169467Y130176D03*
X1216752Y130115D03*
X1212748D03*
X1270005Y130221D03*
X1265997Y130222D03*
X1258500Y338800D03*
X1270500D03*
X1262500D03*
X1266500D03*
X1277500Y397800D03*
Y390300D03*
X1307000Y278800D03*
X1301500Y390300D03*
X1293500D03*
X1297500D03*
X1285500D03*
X1305500D03*
X1289500D03*
X1302128Y677167D03*
X1306128D03*
X1335071Y134411D03*
X1317300Y298200D03*
X1321400D03*
X1315000Y278800D03*
X1313000Y289800D03*
X1314628Y726167D03*
X1326128D03*
X1330128D03*
X1334128D03*
X1338128D03*
X1326100Y734200D03*
X1361500Y266800D03*
G54D33*
X28500Y746900D03*
Y733400D03*
Y729400D03*
X45700Y276800D03*
Y280900D03*
X39100Y394100D03*
X59200Y483000D03*
Y502000D03*
X58800Y708900D03*
X56600Y770800D03*
X70543Y354737D03*
X74200Y506500D03*
Y510500D03*
Y514500D03*
X84400Y529300D03*
X70340Y527270D03*
X84200Y542300D03*
Y546300D03*
X84100Y550400D03*
X84200Y554500D03*
Y558500D03*
X77200Y586000D03*
X90200Y642000D03*
Y646000D03*
X98400Y681900D03*
X81800Y731300D03*
Y727300D03*
X83000Y740900D03*
Y744900D03*
Y766900D03*
X101200Y276300D03*
X104200Y298900D03*
Y302900D03*
X115700Y388600D03*
X115634Y441150D03*
X101700Y569500D03*
X110700Y561500D03*
Y565500D03*
X101700Y592500D03*
X105900Y681900D03*
X119600Y714300D03*
X102600Y727800D03*
X121700Y775000D03*
X153014Y322277D03*
X145513Y322350D03*
X136214Y373985D03*
X160800Y379200D03*
X146698Y420306D03*
X140600Y732300D03*
X132400Y745200D03*
X172484Y186686D03*
Y181686D03*
X197400Y251100D03*
X194015Y289501D03*
X182554Y446672D03*
X174900Y753400D03*
X167700Y808500D03*
X203960Y289306D03*
X213438Y425645D03*
X213238Y441945D03*
X209400Y446000D03*
X213200Y465000D03*
Y469000D03*
Y482000D03*
Y486000D03*
X213300Y494400D03*
X213200Y490000D03*
Y525500D03*
Y521500D03*
Y554500D03*
X226070Y568020D03*
X207200Y729500D03*
Y785000D03*
X239700Y139500D03*
X253928Y124804D03*
X256600Y438600D03*
X259300Y422500D03*
X253400Y443300D03*
X255720Y581381D03*
X233700Y586000D03*
Y590000D03*
X273200Y126000D03*
X272800Y467300D03*
Y485800D03*
X278000Y638900D03*
X285500Y643900D03*
X314700Y221900D03*
X319100Y542500D03*
X338600Y222000D03*
X338300Y335500D03*
X348000Y318500D03*
X463549Y210989D03*
X500232Y130548D03*
X484209Y339041D03*
Y334041D03*
X483900Y393300D03*
X530000Y165815D03*
Y157715D03*
Y161815D03*
X519109Y202072D03*
X511409Y202172D03*
X525800Y340500D03*
X561670Y136909D03*
X554200Y137597D03*
X561731Y334980D03*
X593163Y215308D03*
X575800Y238400D03*
X623063Y217608D03*
X615563Y213608D03*
X608400Y344200D03*
X667200Y212000D03*
X692600Y212200D03*
X681200Y212000D03*
X725913Y2380D03*
X736463Y31882D03*
X720705Y14964D03*
X724359Y28613D03*
X738330Y63910D03*
X717700Y64000D03*
X716810Y55860D03*
Y51796D03*
X756000Y53800D03*
X761150Y75900D03*
X761300Y86500D03*
Y90600D03*
Y102900D03*
Y82300D03*
X768900Y121200D03*
Y133500D03*
X759200Y118800D03*
X778300Y74000D03*
X798300Y74200D03*
X838800Y105600D03*
X810200Y86500D03*
Y90600D03*
X812113Y118898D03*
X849581Y5499D03*
X865200Y32000D03*
Y40000D03*
X865700Y52800D03*
Y48500D03*
X903700Y358500D03*
Y350000D03*
Y345600D03*
X889870Y808230D03*
X908200Y37000D03*
X932300Y78600D03*
X958781Y64624D03*
X992411Y14160D03*
X992569Y27248D03*
Y23121D03*
X1024760Y2024D03*
X1036816Y33563D03*
X1035592Y11076D03*
X1054700Y22200D03*
X1043367Y11296D03*
X1058200Y48700D03*
X1052800Y64100D03*
X1079259Y5500D03*
Y500D03*
X1079269Y22450D03*
X1079824Y39554D03*
X1079269Y26950D03*
X1079824Y35054D03*
X1078539Y14070D03*
X1123700Y235000D03*
X1137700Y234500D03*
X1152200D03*
X1292700Y300000D03*
X1318700Y274500D03*
X1360200Y278500D03*
G54D42*
X47700Y204900D03*
X63050Y200100D03*
X43300Y414000D03*
X83900Y204800D03*
X98450Y199400D03*
X85600Y736400D03*
X85700Y749300D03*
X85600Y762400D03*
X118532Y268820D03*
X128500Y761300D03*
Y756300D03*
X145100Y306400D03*
X134600D03*
X145301Y411131D03*
X133100Y835000D03*
X177500Y748900D03*
Y727900D03*
X170300Y783000D03*
Y804000D03*
X215800Y473500D03*
X209800Y704000D03*
Y725000D03*
Y780500D03*
Y759500D03*
X266600Y651900D03*
X348700Y730900D03*
X497288Y7874D03*
Y31496D03*
Y55118D03*
Y78740D03*
X486500Y367800D03*
Y388800D03*
X569331Y384080D03*
X600163Y257608D03*
X658300Y357600D03*
X723563Y-3650D03*
X873152Y741450D03*
X889400Y739800D03*
X890937Y812539D03*
X1068154Y68898D03*
X1048469D03*
X1087839D03*
G54D144*
X831592Y29400D03*
X833167D03*
X834742D03*
X836317D03*
X837892D03*
X839467D03*
Y51600D03*
X837892D03*
X836317D03*
X834742D03*
X833167D03*
X831592D03*
X841037Y29400D03*
X842612D03*
X844187D03*
X845762D03*
X847337D03*
X848912D03*
Y51600D03*
X847337D03*
X845762D03*
X844187D03*
X842612D03*
X841037D03*
G54D126*
X526215Y184000D03*
X565585D03*
G54D16*
X21900Y192300D03*
X21800Y180800D03*
X23100Y216900D03*
X31500D03*
X38500Y273200D03*
X41500Y261700D03*
X43900Y299900D03*
X54600Y321600D03*
X61799Y372557D03*
X42900Y763200D03*
X67600Y327300D03*
X84700Y328200D03*
X81300D03*
X74000Y572200D03*
X84000Y570700D03*
X80500D03*
X100900Y190600D03*
X130051Y648346D03*
X133299Y574920D03*
X190520Y834501D03*
X194520D03*
X222500Y510200D03*
X226000D03*
X221000Y525700D03*
X207118Y834501D03*
X203118D03*
X219717D03*
X215717D03*
X232315D03*
X228315D03*
X239600Y146100D03*
X244300Y230200D03*
X259857Y510148D03*
X246500Y517700D03*
X241300Y635600D03*
X266906Y768598D03*
X254362Y834501D03*
X250362D03*
X266961D03*
X262961D03*
X267300Y293200D03*
X297729Y354840D03*
X279559Y834501D03*
X275559D03*
X329241Y325130D03*
X301500Y483500D03*
X313354Y834501D03*
X317354D03*
X329953D03*
X325953D03*
X367748D03*
X363748D03*
X342551D03*
X338551D03*
X351150D03*
X355150D03*
X389796D03*
X385796D03*
X398394D03*
X402394D03*
X410993D03*
X414993D03*
X423591D03*
X427591D03*
X459071Y118741D03*
X480406Y820598D03*
X505477Y291940D03*
X525409Y328741D03*
X542120Y215005D03*
X544851Y834501D03*
X548851D03*
X557449D03*
X561449D03*
X570048D03*
X604170Y330540D03*
X574048Y834501D03*
X586646D03*
X582646D03*
X599245D03*
X595245D03*
X619363Y228308D03*
X609500Y353583D03*
X611843Y834501D03*
X607843D03*
X624442D03*
X620442D03*
X637040D03*
X633040D03*
X659087D03*
X655087D03*
X671685D03*
X667685D03*
X684284D03*
X680284D03*
X696882D03*
X692882D03*
X724379D03*
X728379D03*
X736977D03*
X740977D03*
X749576D03*
X753576D03*
X762174D03*
X766174D03*
X774772D03*
X778772D03*
X787370D03*
X791370D03*
X799969D03*
X803969D03*
X812567D03*
X816567D03*
X837764D03*
X849906Y797598D03*
X841764Y834501D03*
X850362D03*
X854362D03*
X896000Y2700D03*
X900522Y13166D03*
X905500Y331200D03*
X1039675Y15287D03*
X1014451Y41506D03*
X1040914Y834501D03*
X1044914D03*
X1053512D03*
X1057512D03*
X1066111D03*
X1070111D03*
X1091307D03*
X1095307D03*
X1103906D03*
X1107906D03*
X1078709D03*
X1082709D03*
X1120504D03*
X1116504D03*
X1129103D03*
X1133103D03*
X1141701D03*
X1145701D03*
X1154299D03*
X1158299D03*
X1176347D03*
X1180347D03*
X1192945D03*
X1188945D03*
X1224441D03*
X1220441D03*
X1237040D03*
X1233040D03*
X1257500Y390200D03*
X1254000D03*
X1249638Y834501D03*
X1245638D03*
X1258237D03*
X1262237D03*
X1274835D03*
X1270835D03*
X1294628Y726067D03*
X1287433Y834501D03*
X1283433D03*
X1312630D03*
X1308630D03*
X1325229D03*
X1321229D03*
X1337827D03*
X1333827D03*
X1346425D03*
X1350425D03*
G54D34*
X25300Y739200D03*
X58300Y327500D03*
X62800Y327200D03*
X64500Y420800D03*
X32000Y473300D03*
X49000D03*
X53200Y466700D03*
X55261Y507441D03*
X51300Y709700D03*
X43300D03*
X57200Y690600D03*
X80300Y259200D03*
X95670Y340811D03*
X91600Y340700D03*
X70591Y363199D03*
X70654Y370860D03*
X80000Y403500D03*
X84274Y399141D03*
X96046Y423330D03*
X92500Y469800D03*
X96700Y469700D03*
X88000Y606900D03*
X72000Y606300D03*
X76000D03*
X66000Y598300D03*
X97500Y631800D03*
X65000Y763100D03*
X108500Y294700D03*
X128180Y311014D03*
X103998Y340850D03*
X99887Y340875D03*
X103617Y332815D03*
X100200Y384900D03*
X100076Y430730D03*
X111500Y457800D03*
X107500D03*
X106900Y732100D03*
X126000Y777300D03*
X151600Y406300D03*
X133000Y457800D03*
X137000D03*
X142000Y453300D03*
X160000Y774800D03*
X164500Y812800D03*
X196018Y196356D03*
X191018D03*
X197841Y430442D03*
X184116Y458610D03*
X192733Y458132D03*
X188150Y458505D03*
X172800Y457800D03*
X197500Y570332D03*
X191500Y598300D03*
X195500Y590800D03*
Y583300D03*
X199500Y695800D03*
X167200Y719700D03*
X199500Y751300D03*
X171700Y757700D03*
X224900Y109400D03*
X224600Y120100D03*
X207369Y147784D03*
X220969Y434972D03*
X209400Y450100D03*
X213500D03*
X225000Y518400D03*
X229000Y525800D03*
X201500Y570332D03*
X226200Y572462D03*
X204000Y733800D03*
Y789300D03*
X261200Y101900D03*
X235505Y144662D03*
X236331Y230380D03*
X258900Y293600D03*
X263000Y293400D03*
X266729Y345940D03*
X244900Y430900D03*
X262900Y430400D03*
X257500Y447538D03*
X253400Y447500D03*
X242500Y525800D03*
X253500D03*
X258000Y517800D03*
X245300Y635700D03*
X277500Y133800D03*
X272900Y293300D03*
X299639Y332701D03*
X294406Y719698D03*
X290406D03*
X286406D03*
X282406D03*
X298406D03*
X278406Y768698D03*
X274406D03*
X282478Y768731D03*
X316646Y293575D03*
X302700Y294562D03*
X320662Y293590D03*
X315300Y337300D03*
X310406Y719698D03*
X306406D03*
X302406D03*
X314500Y719800D03*
X355200Y328800D03*
X466000Y65500D03*
X457700D03*
X474400D03*
X500238Y130550D03*
X478800Y119300D03*
X477466Y182820D03*
X471681Y306512D03*
X476200Y359600D03*
X480700Y397600D03*
X499906Y771698D03*
X495906D03*
X491906Y820698D03*
X487906D03*
X495978Y820731D03*
X504248Y130550D03*
X528709Y291483D03*
X523906Y771698D03*
X507906D03*
X519906D03*
X503906D03*
X515906D03*
X511906D03*
X528100Y771600D03*
X558263Y133520D03*
X570100Y202300D03*
X541681Y291076D03*
X563531Y373380D03*
X558531Y380880D03*
X631363Y228408D03*
X623363D03*
X608090Y330660D03*
X632000Y333900D03*
X636000D03*
X617000Y375900D03*
X623000D03*
X640000Y333900D03*
X718302Y3324D03*
X736500Y24300D03*
X713375Y24502D03*
X724820Y15040D03*
X720700Y14970D03*
X728960Y15130D03*
X720840Y56440D03*
X742700Y11600D03*
X769400Y104200D03*
X838252Y14300D03*
X834252D03*
X830252D03*
X826252D03*
X822252D03*
X854400D03*
X846252D03*
X842252D03*
X873406Y748624D03*
X869406Y748698D03*
X865406D03*
X861406Y797698D03*
X857406D03*
X865478Y797731D03*
X891301Y13177D03*
X877406Y748698D03*
X893406D03*
X889406D03*
X885406D03*
X881406D03*
X897600Y748600D03*
X938000Y23300D03*
X911000Y89800D03*
X915500D03*
X920000D03*
X933500D03*
X929000D03*
X924500D03*
X938000D03*
X956000D03*
X1005176Y41562D03*
X1000683Y45750D03*
X1010676Y41562D03*
X1068809Y13342D03*
X1249679Y129895D03*
X1253719D03*
X1274500Y338800D03*
X1278500D03*
X1265500Y390300D03*
X1269500D03*
X1273500D03*
X1261500D03*
X1304000Y12800D03*
Y36300D03*
Y59800D03*
Y83300D03*
X1311000Y278800D03*
X1282500Y338800D03*
X1286500D03*
X1290500D03*
X1294500D03*
X1302500D03*
X1298500D03*
X1310128Y677167D03*
X1306128Y726167D03*
X1302128D03*
X1310200Y726200D03*
X1335100Y141970D03*
X1338128Y677167D03*
X1322128D03*
X1334128D03*
X1318128D03*
X1330128D03*
X1314128D03*
X1326128D03*
X1342300Y676800D03*
X1322400Y669600D03*
X1378134Y173509D03*
X1359124Y171420D03*
X1359011Y178984D03*
G54D127*
X532909Y331641D03*
Y321441D03*
G54D25*
X31500Y441800D03*
Y434200D03*
X31000Y423800D03*
Y416200D03*
X37300Y712200D03*
Y704600D03*
X124051Y647136D03*
Y654736D03*
X153421Y301558D03*
Y309158D03*
X161400Y301600D03*
Y309200D03*
X276300Y621600D03*
Y629200D03*
Y644100D03*
Y651700D03*
X335000Y179700D03*
Y187300D03*
X343000Y179700D03*
Y187300D03*
X589500Y356300D03*
Y348700D03*
X574000Y356300D03*
Y348700D03*
X581700Y356300D03*
Y348700D03*
X660263Y228808D03*
Y236408D03*
X704700Y278200D03*
Y285800D03*
X732600Y238700D03*
X724600D03*
X716600D03*
X708600D03*
X732600Y246300D03*
X724600D03*
X716600D03*
X708600D03*
X712300Y278200D03*
X719900D03*
X727500D03*
X735100D03*
X712300Y285800D03*
X719900D03*
X727500D03*
X735100D03*
X748237Y205992D03*
Y198392D03*
X923900Y47800D03*
Y55400D03*
X971400Y39400D03*
Y31800D03*
Y48800D03*
Y56400D03*
X979400Y39400D03*
Y31800D03*
Y48800D03*
Y56400D03*
X1177000Y228600D03*
Y221000D03*
X1168000Y228600D03*
Y221000D03*
X1177000Y267200D03*
Y274800D03*
X1168000Y267200D03*
Y274800D03*
X1213000Y228600D03*
Y221000D03*
X1204000Y228600D03*
Y221000D03*
X1195000Y228600D03*
Y221000D03*
X1186000Y228600D03*
Y221000D03*
X1212500Y267200D03*
Y274800D03*
X1195000Y267200D03*
Y274800D03*
X1204000Y267200D03*
Y274800D03*
X1186000Y267200D03*
Y274800D03*
G54D61*
X54300Y734900D03*
X633000Y356600D03*
G54D70*
X95252Y576388D03*
Y585612D03*
X101748Y576388D03*
Y585612D03*
G54D145*
X889700Y23000D03*
X895300D03*
G54D109*
X266231Y245001D03*
X261231D03*
X256231D03*
X251231D03*
X246231D03*
X241231D03*
X236231D03*
Y283559D03*
X241231D03*
X246231D03*
X251231D03*
X256231D03*
X261231D03*
X266231D03*
X271231Y245001D03*
Y283559D03*
X332834Y244932D03*
X327834D03*
X322834D03*
X317834D03*
X312834D03*
X307834D03*
X302834D03*
Y283490D03*
X307834D03*
X312834D03*
X317834D03*
X322834D03*
X327834D03*
X332834D03*
X337834Y244932D03*
Y283490D03*
G54D118*
X336141Y323975D03*
Y325945D03*
Y327915D03*
Y329885D03*
X345341D03*
Y327915D03*
Y325945D03*
Y323975D03*
X872850Y-1435D03*
Y530D03*
Y2500D03*
Y4470D03*
Y6435D03*
X889150D03*
Y4470D03*
Y2500D03*
Y530D03*
Y-1435D03*
G54D136*
X635953Y346807D03*
X633984D03*
X632016D03*
X630047D03*
Y366393D03*
X632016D03*
X633984D03*
X635953D03*
X628079Y346807D03*
Y366393D03*
X637921Y346807D03*
Y366393D03*
G54D154*
X1273486Y243500D03*
X1314514D03*
G54D43*
X42100Y204900D03*
X57450Y200100D03*
X37700Y414000D03*
X78300Y204800D03*
X92850Y199400D03*
X80000Y736400D03*
X80100Y749300D03*
X80000Y762400D03*
X112932Y268820D03*
X129000Y306400D03*
X122900Y761300D03*
Y756300D03*
X127500Y835000D03*
X139500Y306400D03*
X139701Y411131D03*
X164700Y783000D03*
Y804000D03*
X171900Y748900D03*
Y727900D03*
X210200Y473500D03*
X204200Y704000D03*
Y725000D03*
Y780500D03*
Y759500D03*
X261000Y651900D03*
X343100Y730900D03*
X491688Y7874D03*
Y31496D03*
Y55118D03*
Y78740D03*
X480900Y367800D03*
Y388800D03*
X563731Y384080D03*
X594563Y257608D03*
X652700Y357600D03*
X717963Y-3650D03*
X867552Y741450D03*
X883800Y739800D03*
X885337Y812539D03*
X1042869Y68898D03*
X1062554D03*
X1082239D03*
G54D52*
X63500Y353960D03*
X116948Y512145D03*
X120098D03*
X123247D03*
X126397D03*
X129547D03*
X116948Y508996D03*
X120098D03*
X123247D03*
X126397D03*
X129547D03*
X116948Y505846D03*
X120098D03*
X123247D03*
X126397D03*
X129547D03*
X116948Y502696D03*
X120098D03*
X123247D03*
X126397D03*
X129547D03*
X116948Y499547D03*
X120098D03*
X123247D03*
X126397D03*
X129547D03*
X116948Y496397D03*
X120098D03*
X123247D03*
X126397D03*
X129547D03*
X116948Y493248D03*
X120098D03*
X123247D03*
X126397D03*
X129547D03*
X116948Y490098D03*
X120098D03*
X123247D03*
X126397D03*
X129547D03*
X126397Y486948D03*
X129547D03*
X126397Y483799D03*
X129547D03*
X126397Y480649D03*
X129547D03*
X126397Y546791D03*
X129547D03*
X126397Y543641D03*
X129547D03*
X126397Y540492D03*
X129547D03*
X116948Y537342D03*
X120098D03*
X123247D03*
X126397D03*
X129547D03*
X116948Y534192D03*
X120098D03*
X123247D03*
X126397D03*
X129547D03*
X116948Y531043D03*
X120098D03*
X123247D03*
X126397D03*
X129547D03*
X116948Y527893D03*
X120098D03*
X123247D03*
X126397D03*
X129547D03*
X116948Y524744D03*
X120098D03*
X123247D03*
X126397D03*
X129547D03*
X116948Y521594D03*
X120098D03*
X123247D03*
X126397D03*
X129547D03*
X116948Y518444D03*
X120098D03*
X123247D03*
X126397D03*
X129547D03*
X116948Y515295D03*
X120098D03*
X123247D03*
X126397D03*
X129547D03*
X117197Y593622D03*
Y596771D03*
Y599921D03*
Y612519D03*
X120347Y593622D03*
Y596771D03*
Y599921D03*
Y612519D03*
X123496Y593622D03*
Y596771D03*
Y599921D03*
Y612519D03*
X126646Y593622D03*
Y596771D03*
Y599921D03*
Y612519D03*
X129795Y593622D03*
Y596771D03*
Y599921D03*
Y612519D03*
X117197Y615669D03*
Y618818D03*
X120347Y615669D03*
Y618818D03*
X123496Y615669D03*
Y618818D03*
X126646Y615669D03*
Y618818D03*
X129795Y615669D03*
Y618818D03*
X132696Y512145D03*
X142145D03*
X145295D03*
X148444D03*
X151594D03*
X154743D03*
X157893D03*
X132696Y508996D03*
X142145D03*
X145295D03*
X148444D03*
X151594D03*
X154743D03*
X157893D03*
X132696Y505846D03*
X142145D03*
X145295D03*
X148444D03*
X151594D03*
X154743D03*
X157893D03*
X132696Y502696D03*
X138995Y496397D03*
X142145D03*
X145295D03*
X148444D03*
X151594D03*
X154743D03*
X157893D03*
X161043D03*
X132696Y493248D03*
X135846D03*
X138995D03*
X142145D03*
X145295D03*
X148444D03*
X151594D03*
X154743D03*
X157893D03*
X161043D03*
X164192D03*
X132696Y490098D03*
X135846D03*
X138995D03*
X142145D03*
X145295D03*
X148444D03*
X151594D03*
X154743D03*
X157893D03*
X161043D03*
X164192D03*
X132696Y486948D03*
X135846D03*
X138995D03*
X142145D03*
X145295D03*
X148444D03*
X151594D03*
X154743D03*
X157893D03*
X161043D03*
X164192D03*
X132696Y483799D03*
X135846D03*
X138995D03*
X142145D03*
X145295D03*
X148444D03*
X151594D03*
X154743D03*
X157893D03*
X161043D03*
X164192D03*
X132696Y480649D03*
X135846D03*
X138995D03*
X142145D03*
X145295D03*
X148444D03*
X151594D03*
X154743D03*
X157893D03*
X161043D03*
X164192D03*
X132696Y546791D03*
X135846D03*
X138995D03*
X142145D03*
X145295D03*
X148444D03*
X151594D03*
X154743D03*
X157893D03*
X161043D03*
X164192D03*
X132696Y543641D03*
X135846D03*
X138995D03*
X142145D03*
X145295D03*
X148444D03*
X151594D03*
X154743D03*
X157893D03*
X161043D03*
X164192D03*
X132696Y540492D03*
X135846D03*
X138995D03*
X142145D03*
X145295D03*
X148444D03*
X151594D03*
X154743D03*
X157893D03*
X161043D03*
X164192D03*
X132696Y537342D03*
X135846D03*
X138995D03*
X142145D03*
X145295D03*
X148444D03*
X151594D03*
X154743D03*
X157893D03*
X161043D03*
X164192D03*
X132696Y534192D03*
X135846D03*
X138995D03*
X142145D03*
X145295D03*
X148444D03*
X151594D03*
X154743D03*
X157893D03*
X161043D03*
X164192D03*
X138995Y531043D03*
X142145D03*
X145295D03*
X148444D03*
X151594D03*
X154743D03*
X157893D03*
X161043D03*
X132696Y524744D03*
Y521594D03*
X142145D03*
X145295D03*
X148444D03*
X151594D03*
X154743D03*
X157893D03*
X132696Y518444D03*
X142145D03*
X145295D03*
X148444D03*
X151594D03*
X154743D03*
X157893D03*
X132696Y515295D03*
X142145D03*
X145295D03*
X148444D03*
X151594D03*
X154743D03*
X157893D03*
X132945Y593622D03*
Y596771D03*
Y599921D03*
Y612519D03*
X136095Y593622D03*
Y596771D03*
Y599921D03*
Y612519D03*
X139244Y593622D03*
Y596771D03*
Y599921D03*
Y612519D03*
X142394Y593622D03*
Y596771D03*
Y599921D03*
Y612519D03*
X145543Y593622D03*
Y596771D03*
Y599921D03*
Y612519D03*
X148693Y593622D03*
Y596771D03*
Y599921D03*
Y612519D03*
X151843Y593622D03*
Y596771D03*
Y599921D03*
Y612519D03*
X154992Y593622D03*
Y596771D03*
Y599921D03*
Y612519D03*
X158142Y593622D03*
Y596771D03*
Y599921D03*
Y612519D03*
X161291Y593622D03*
Y596771D03*
Y599921D03*
Y612519D03*
X164441Y593622D03*
Y596771D03*
Y599921D03*
Y612519D03*
X132945Y615669D03*
Y618818D03*
X136095Y615669D03*
Y618818D03*
X139244Y615669D03*
Y618818D03*
X142394Y615669D03*
Y618818D03*
X145543Y615669D03*
Y618818D03*
X148693Y615669D03*
Y618818D03*
X151843Y615669D03*
Y618818D03*
X154992Y615669D03*
Y618818D03*
X158142Y615669D03*
Y618818D03*
X161291Y615669D03*
Y618818D03*
X164441Y615669D03*
Y618818D03*
X167342Y512145D03*
X170491D03*
X173641D03*
X176791D03*
X179940D03*
X183090D03*
X167342Y508996D03*
X170491D03*
X173641D03*
X176791D03*
X179940D03*
X183090D03*
X167342Y505846D03*
X170491D03*
X173641D03*
X176791D03*
X179940D03*
X183090D03*
X167342Y502696D03*
X170491D03*
X173641D03*
X176791D03*
X179940D03*
X183090D03*
X170491Y499547D03*
X173641D03*
X176791D03*
X179940D03*
X183090D03*
X170491Y496397D03*
X173641D03*
X176791D03*
X179940D03*
X183090D03*
X167342Y493248D03*
X170491D03*
X173641D03*
X176791D03*
X179940D03*
X183090D03*
X167342Y490098D03*
X170491D03*
X173641D03*
X176791D03*
X179940D03*
X183090D03*
X167342Y486948D03*
X170491D03*
X173641D03*
X167342Y483799D03*
X170491D03*
X173641D03*
X167342Y480649D03*
X170491D03*
X173641D03*
X167342Y546791D03*
X170491D03*
X173641D03*
X167342Y543641D03*
X170491D03*
X173641D03*
X167342Y540492D03*
X170491D03*
X173641D03*
X167342Y537342D03*
X170491D03*
X173641D03*
X176791D03*
X179940D03*
X183090D03*
X167342Y534192D03*
X170491D03*
X173641D03*
X176791D03*
X179940D03*
X183090D03*
X170491Y531043D03*
X173641D03*
X176791D03*
X179940D03*
X183090D03*
X170491Y527893D03*
X173641D03*
X176791D03*
X179940D03*
X183090D03*
X167342Y524744D03*
X170491D03*
X173641D03*
X176791D03*
X179940D03*
X183090D03*
X167342Y521594D03*
X170491D03*
X173641D03*
X176791D03*
X179940D03*
X183090D03*
X167342Y518444D03*
X170491D03*
X173641D03*
X176791D03*
X179940D03*
X183090D03*
X167342Y515295D03*
X170491D03*
X173641D03*
X176791D03*
X179940D03*
X183090D03*
X1293280Y345770D03*
X1289960Y349900D03*
X1299000Y347500D03*
G54D35*
X25300Y742600D03*
X58300Y330900D03*
X62800Y330600D03*
X64500Y424200D03*
X32000Y476700D03*
X49000D03*
X53200Y470100D03*
X55261Y510841D03*
X51300Y713100D03*
X43300D03*
X57200Y694000D03*
X80300Y262600D03*
X95670Y344211D03*
X91600Y344100D03*
X70591Y366599D03*
X70654Y374260D03*
X80000Y406900D03*
X84274Y402541D03*
X96046Y426730D03*
X92500Y473200D03*
X96700Y473100D03*
X88000Y610300D03*
X72000Y609700D03*
X76000D03*
X66000Y601700D03*
X97500Y635200D03*
X65000Y766500D03*
X108500Y298100D03*
X128180Y314414D03*
X103998Y344250D03*
X99887Y344275D03*
X103617Y336215D03*
X100200Y388300D03*
X100076Y434130D03*
X111500Y461200D03*
X107500D03*
X106900Y735500D03*
X126000Y780700D03*
X151600Y409700D03*
X133000Y461200D03*
X137000D03*
X142000Y456700D03*
X160000Y778200D03*
X164500Y816200D03*
X196018Y199756D03*
X191018D03*
X197841Y433842D03*
X184116Y462010D03*
X192733Y461532D03*
X188150Y461905D03*
X172800Y461200D03*
X197500Y573732D03*
X191500Y601700D03*
X195500Y594200D03*
Y586700D03*
X199500Y699200D03*
X167200Y723100D03*
X199500Y754700D03*
X171700Y761100D03*
X224900Y112800D03*
X224600Y123500D03*
X207369Y151184D03*
X220969Y438372D03*
X209400Y453500D03*
X213500D03*
X225000Y521800D03*
X229000Y529200D03*
X201500Y573732D03*
X226200Y575862D03*
X204000Y737200D03*
Y792700D03*
X261200Y105300D03*
X235505Y148062D03*
X236331Y233780D03*
X258900Y297000D03*
X263000Y296800D03*
X266729Y349340D03*
X244900Y434300D03*
X262900Y433800D03*
X257500Y450938D03*
X253400Y450900D03*
X242500Y529200D03*
X253500D03*
X258000Y521200D03*
X245300Y639100D03*
X277500Y137200D03*
X272900Y296700D03*
X299639Y336101D03*
X294406Y723098D03*
X290406D03*
X286406D03*
X282406D03*
X298406D03*
X278406Y772098D03*
X274406D03*
X282478Y772131D03*
X316646Y296975D03*
X302700Y297962D03*
X320662Y296990D03*
X315300Y340700D03*
X310406Y723098D03*
X306406D03*
X302406D03*
X314500Y723200D03*
X355200Y332200D03*
X466000Y68900D03*
X457700D03*
X474400D03*
X500238Y133950D03*
X478800Y122700D03*
X477466Y186220D03*
X471681Y309912D03*
X476200Y363000D03*
X480700Y401000D03*
X499906Y775098D03*
X495906D03*
X491906Y824098D03*
X487906D03*
X495978Y824131D03*
X504248Y133950D03*
X528709Y294883D03*
X523906Y775098D03*
X507906D03*
X519906D03*
X503906D03*
X515906D03*
X511906D03*
X528100Y775000D03*
X558263Y136920D03*
X570100Y205700D03*
X541681Y294476D03*
X563531Y376780D03*
X558531Y384280D03*
X631363Y231808D03*
X623363D03*
X608090Y334060D03*
X632000Y337300D03*
X636000D03*
X617000Y379300D03*
X623000D03*
X640000Y337300D03*
X718302Y6724D03*
X736500Y27700D03*
X713375Y27902D03*
X724820Y18440D03*
X720700Y18370D03*
X728960Y18530D03*
X720840Y59840D03*
X742700Y15000D03*
X769400Y107600D03*
X838252Y17700D03*
X834252D03*
X830252D03*
X826252D03*
X822252D03*
X854400D03*
X846252D03*
X842252D03*
X873406Y752024D03*
X869406Y752098D03*
X865406D03*
X861406Y801098D03*
X857406D03*
X865478Y801131D03*
X891301Y16577D03*
X877406Y752098D03*
X893406D03*
X889406D03*
X885406D03*
X881406D03*
X897600Y752000D03*
X938000Y26700D03*
X911000Y93200D03*
X915500D03*
X920000D03*
X933500D03*
X929000D03*
X924500D03*
X938000D03*
X956000D03*
X1005176Y44962D03*
X1000683Y49150D03*
X1010676Y44962D03*
X1068809Y16742D03*
X1249679Y133295D03*
X1253719D03*
X1274500Y342200D03*
X1278500D03*
X1265500Y393700D03*
X1269500D03*
X1273500D03*
X1261500D03*
X1304000Y16200D03*
Y39700D03*
Y63200D03*
Y86700D03*
X1311000Y282200D03*
X1282500Y342200D03*
X1286500D03*
X1290500D03*
X1294500D03*
X1302500D03*
X1298500D03*
X1310128Y680567D03*
X1306128Y729567D03*
X1302128D03*
X1310200Y729600D03*
X1335100Y145370D03*
X1338128Y680567D03*
X1322128D03*
X1334128D03*
X1318128D03*
X1330128D03*
X1314128D03*
X1326128D03*
X1342300Y680200D03*
X1322400Y673000D03*
X1359124Y174820D03*
X1378134Y176909D03*
X1359011Y182384D03*
G54D62*
X88276Y248031D03*
G54D44*
X54378Y237402D03*
G54D128*
X559109Y312241D03*
X574609D03*
X1353250Y192000D03*
X1368750D03*
G54D71*
X91750Y600560D03*
Y595440D03*
X85250D03*
Y598000D03*
Y600560D03*
X105896Y362064D03*
Y359504D03*
Y356944D03*
X112396D03*
Y362064D03*
X297512Y470240D03*
Y472800D03*
Y475360D03*
X291012D03*
Y470240D03*
X743250Y28640D03*
Y33760D03*
X749750D03*
Y31200D03*
Y28640D03*
G54D146*
X885300Y64650D03*
Y57150D03*
X892900Y64650D03*
G54D155*
X1309410Y170203D03*
G54D137*
X623007Y349710D03*
Y363490D03*
X642993D03*
Y349710D03*
G54D119*
X476614Y167493D03*
Y162493D03*
Y157493D03*
G54D17*
X27300Y223000D03*
X37700Y693300D03*
X76450Y704950D03*
X114364Y132099D03*
X108224Y164187D03*
X123680Y315514D03*
X132400Y727600D03*
X111400D03*
X181838Y132011D03*
X548531Y368380D03*
X580178Y238769D03*
X994597Y58669D03*
G54D53*
X48000Y426000D03*
G54D80*
X121504Y248031D03*
G54D26*
X25000Y429700D03*
X47800Y763600D03*
X64900Y771100D03*
X68100Y259500D03*
X65965Y367608D03*
X69800Y763100D03*
X111400Y732500D03*
X132400D03*
X171094Y238161D03*
X290200Y706500D03*
X520909Y323741D03*
X612830Y335850D03*
X1028500Y65200D03*
X1357000Y265700D03*
G54D27*
X25000Y435300D03*
X47800Y769200D03*
X64900Y776700D03*
X68100Y265100D03*
X65965Y373208D03*
X69800Y768700D03*
X111400Y738100D03*
X132400D03*
X171094Y243761D03*
X290200Y712100D03*
X520909Y329341D03*
X612830Y341450D03*
X1028500Y70800D03*
X1357000Y271300D03*
G54D72*
X84800Y590300D03*
X121700Y173000D03*
X107500Y203300D03*
X121700Y185000D03*
Y181000D03*
Y177000D03*
Y189000D03*
X104058Y427004D03*
X104062Y430420D03*
X134100Y264300D03*
X141637Y407034D03*
X180800Y289472D03*
X199700Y580500D03*
X209700Y517500D03*
X261429Y338640D03*
X252188Y577665D03*
X241500Y643400D03*
X263500Y647400D03*
X277700Y130000D03*
X287500Y465000D03*
X329658Y292248D03*
X455892Y114254D03*
X558231Y338980D03*
X619563Y221608D03*
X738800Y20300D03*
X713200Y81500D03*
Y78000D03*
Y96500D03*
Y93000D03*
Y105500D03*
Y102000D03*
Y85000D03*
Y88500D03*
Y117500D03*
Y114000D03*
X757400Y109300D03*
Y112800D03*
X802800Y106300D03*
Y102800D03*
X835186Y161691D03*
Y158240D03*
X927200Y27270D03*
X1054600Y44400D03*
X1317200Y290000D03*
G54D156*
X1311262Y175228D03*
X1290978D03*
X1311262Y181958D03*
X1290978D03*
G54D63*
X95047Y238996D03*
X97016Y257066D03*
X114733Y238996D03*
X110796D03*
X106859D03*
X102921D03*
X98984D03*
X112764Y257066D03*
X108827D03*
X104890D03*
X100953D03*
G54D54*
X65700Y430500D03*
Y438500D03*
X47200Y439500D03*
X54800D03*
X60200Y572500D03*
Y564500D03*
X73300Y430500D03*
Y438500D03*
X67800Y572500D03*
Y564500D03*
X120700Y203500D03*
X128300D03*
X120700Y195500D03*
X128300D03*
X120700Y211500D03*
X128300D03*
X127300Y277400D03*
X119700D03*
X150600Y266100D03*
X143000D03*
X229200Y177500D03*
Y169000D03*
Y186000D03*
X231200Y509500D03*
X236800Y177500D03*
X248700Y171922D03*
X256300D03*
X236800Y169000D03*
X248700Y179722D03*
X256300D03*
X248700Y187722D03*
X256300D03*
X236800Y186000D03*
X238800Y509500D03*
X261600Y606400D03*
X254000D03*
X261600Y614400D03*
X254000D03*
X261600Y622400D03*
X254000D03*
X304639Y326201D03*
X312239D03*
X510677Y293740D03*
X518277D03*
X570063Y253608D03*
Y245608D03*
X569200Y375000D03*
X558331Y375080D03*
X550731D03*
X595063Y264108D03*
X602663D03*
X577663Y253608D03*
Y245608D03*
X576800Y375000D03*
X1346300Y240000D03*
X1338700D03*
X1359681Y240509D03*
X1367281D03*
X1359740Y248121D03*
X1367340D03*
G54D36*
X39370Y801181D03*
X293110Y55906D03*
X336417Y90551D03*
X789850Y283464D03*
X1333661Y55906D03*
X1360630Y135826D03*
Y801181D03*
X1376968Y90551D03*
G54D45*
X54083Y308727D03*
Y306758D03*
Y304790D03*
Y302821D03*
Y300853D03*
Y298884D03*
Y296916D03*
Y294947D03*
Y292979D03*
Y291010D03*
Y289042D03*
Y287073D03*
Y285105D03*
Y310695D03*
X88917Y285105D03*
Y287073D03*
Y289042D03*
Y291010D03*
Y292979D03*
Y294947D03*
Y296916D03*
Y298884D03*
Y300853D03*
Y302821D03*
Y304790D03*
Y306758D03*
Y308727D03*
Y310695D03*
G54D81*
X128850Y287500D03*
X125100D03*
X121350D03*
Y298100D03*
X125100D03*
X128850D03*
X153130Y170531D03*
X149380D03*
X145630D03*
Y181131D03*
X149380D03*
X153130D03*
G54D90*
X149260Y228500D03*
X156740D03*
Y219500D03*
X153000D03*
X149260D03*
G54D138*
X623207Y361521D03*
Y351679D03*
Y359553D03*
Y357584D03*
Y355616D03*
Y353647D03*
X642793Y361521D03*
Y359553D03*
Y357584D03*
Y355616D03*
Y353647D03*
Y351679D03*
G54D18*
X27300Y217400D03*
X37700Y687700D03*
X76450Y699350D03*
X114364Y126499D03*
X108224Y158587D03*
X123680Y309914D03*
X132400Y722000D03*
X111400D03*
X181838Y126411D03*
X548531Y362780D03*
X580178Y233169D03*
X994597Y53069D03*
G54D129*
X560531Y358080D03*
G54D147*
X892900Y57935D03*
X1049935Y28600D03*
G54D73*
X88400Y590300D03*
X125300Y173000D03*
X111100Y203300D03*
X125300Y185000D03*
Y181000D03*
Y177000D03*
Y189000D03*
X107658Y427004D03*
X107662Y430420D03*
X137700Y264300D03*
X145237Y407034D03*
X184400Y289472D03*
X213300Y517500D03*
X203300Y580500D03*
X265029Y338640D03*
X255788Y577665D03*
X245100Y643400D03*
X267100Y647400D03*
X281300Y130000D03*
X291100Y465000D03*
X333258Y292248D03*
X459492Y114254D03*
X561831Y338980D03*
X623163Y221608D03*
X716800Y81500D03*
Y78000D03*
Y96500D03*
Y93000D03*
Y105500D03*
Y102000D03*
Y85000D03*
Y88500D03*
Y117500D03*
Y114000D03*
X742400Y20300D03*
X761000Y109300D03*
Y112800D03*
X806400Y106300D03*
Y102800D03*
X838786Y161691D03*
Y158240D03*
X930800Y27270D03*
X1058200Y44400D03*
X1320800Y290000D03*
G54D19*
X28400Y270875D03*
Y287925D03*
G54D28*
X25200Y424000D03*
X28500Y720400D03*
X31548Y310872D03*
X31612Y306674D03*
X45000Y321400D03*
X32700Y429000D03*
X40200Y466000D03*
X60800Y470100D03*
Y474200D03*
X40700Y484500D03*
X34000Y533500D03*
X58800Y713000D03*
X79691Y365075D03*
X79505Y360727D03*
X89100Y360000D03*
X84390Y392665D03*
X97049Y477241D03*
X82969Y513090D03*
X83844Y508831D03*
X95700Y506000D03*
X83844Y504831D03*
X66969Y502220D03*
X95700Y526500D03*
Y522500D03*
Y530500D03*
X82969Y517090D03*
X95700Y534500D03*
Y518500D03*
Y538500D03*
X84200Y534300D03*
Y538300D03*
X71120Y535931D03*
Y531831D03*
X83700Y606500D03*
X77200Y582000D03*
X83300Y681900D03*
X90900D03*
X79200Y723200D03*
X83000Y753700D03*
Y757900D03*
X110500Y212200D03*
X109500Y230100D03*
X101300Y272000D03*
X99007Y281582D03*
X104200Y294900D03*
Y290900D03*
X103890Y319780D03*
X103940Y315650D03*
X104100Y324100D03*
X104000Y328600D03*
X126400Y392300D03*
X102600Y732300D03*
X118200Y756000D03*
X135880Y311214D03*
X157500Y402200D03*
X146769Y636620D03*
X137251Y648436D03*
X140600Y727800D03*
X160200Y808500D03*
X182539Y450747D03*
X166027Y447721D03*
X167400Y753400D03*
X211149Y143587D03*
X206300Y251000D03*
X216900Y446000D03*
X223200Y469000D03*
Y465000D03*
X213200Y478000D03*
X221700Y486600D03*
X213200Y502000D03*
Y506000D03*
X227350Y491200D03*
X227362Y495300D03*
X213200Y534500D03*
Y542500D03*
Y538500D03*
Y550500D03*
Y570500D03*
X226072Y563994D03*
X199700Y729500D03*
Y785000D03*
X251800Y339700D03*
X264929Y334140D03*
X260900Y443300D03*
X281200Y126000D03*
X288740Y149350D03*
X281200Y145500D03*
X297688Y578165D03*
Y583165D03*
Y588665D03*
X312482Y293550D03*
X319100Y538300D03*
X347400Y335600D03*
X336500Y318900D03*
X486660Y13180D03*
X486670Y26720D03*
X486700Y49880D03*
Y73380D03*
X473360Y143008D03*
X494300Y166000D03*
X476400Y393300D03*
X507642Y130547D03*
X508500Y186500D03*
X554180Y133550D03*
X538412Y159035D03*
X538325Y163463D03*
X549399Y291069D03*
X561731Y342980D03*
X584763Y228608D03*
X593163Y211308D03*
X623263Y209608D03*
X630863Y209408D03*
Y217608D03*
X625563Y238108D03*
X630863Y213508D03*
X608400Y348200D03*
X655700Y340100D03*
X663200D03*
X655700Y344600D03*
Y372100D03*
Y376600D03*
X663200D03*
X655700Y367100D03*
Y362100D03*
Y352600D03*
Y348600D03*
X736500Y14000D03*
X738800Y114020D03*
X738780Y109410D03*
X759800Y35100D03*
Y26200D03*
X767600D03*
X757200Y64000D03*
X770900Y74000D03*
X761300Y98800D03*
Y94700D03*
X768900Y129400D03*
Y125300D03*
X801010Y26343D03*
X787600Y74100D03*
X777000Y135200D03*
X810200Y82400D03*
X810300Y94600D03*
Y98700D03*
X831260Y105630D03*
X815125Y123631D03*
Y127631D03*
X863900Y3900D03*
X865200Y28000D03*
Y36000D03*
X865700Y8000D03*
X865533Y44034D03*
X874700Y52800D03*
X903700Y341600D03*
Y363000D03*
Y354000D03*
X908200Y33000D03*
Y29000D03*
Y41000D03*
X930670Y23540D03*
X988117Y18587D03*
X1037021Y26921D03*
X1015178Y49109D03*
X1052186Y11208D03*
X1058060Y69355D03*
X1065883Y48832D03*
X1090700Y500D03*
Y5000D03*
X1090320Y27440D03*
X1090704Y36383D03*
X1090320Y22940D03*
X1090704Y40883D03*
X1079176Y18266D03*
X1089925Y14177D03*
X1090127Y18525D03*
X1077700Y68500D03*
X1249668Y141179D03*
X1248184Y145217D03*
X1292700Y295000D03*
X1313510Y145310D03*
X1314226Y151199D03*
X1328700Y290500D03*
X1320700Y294000D03*
X1366618Y168102D03*
G54D157*
X1307100Y296700D03*
X1298300Y300700D03*
Y292700D03*
G54D91*
X139000Y218419D03*
Y229581D03*
G54D46*
X53583Y283136D03*
Y312664D03*
X54100Y427970D03*
Y426000D03*
Y424030D03*
Y422065D03*
X41900D03*
Y424030D03*
Y426000D03*
Y427970D03*
X54100Y429935D03*
X41900D03*
X89417Y283136D03*
Y312664D03*
X253200Y633930D03*
Y635900D03*
Y637870D03*
Y639835D03*
X265400D03*
Y637870D03*
Y635900D03*
Y633930D03*
X253200Y631965D03*
X265400D03*
G54D148*
X876378Y129921D03*
Y133858D03*
Y141732D03*
X880315Y129921D03*
Y133858D03*
Y137795D03*
Y141732D03*
X884252Y129921D03*
Y133858D03*
Y137795D03*
Y141732D03*
X888189Y118110D03*
Y122047D03*
Y125984D03*
Y129921D03*
Y133858D03*
Y137795D03*
Y141732D03*
X892126Y122047D03*
Y125984D03*
Y129921D03*
Y133858D03*
Y137795D03*
Y141732D03*
X896063Y118110D03*
Y122047D03*
Y125984D03*
Y129921D03*
Y133858D03*
Y137795D03*
Y141732D03*
X900000Y122047D03*
Y125984D03*
Y129921D03*
Y133858D03*
Y137795D03*
Y141732D03*
X903937Y118110D03*
Y122047D03*
Y125984D03*
Y129921D03*
Y133858D03*
Y137795D03*
Y141732D03*
X907874Y118110D03*
Y122047D03*
Y125984D03*
Y129921D03*
Y133858D03*
Y137795D03*
Y141732D03*
X876378Y149606D03*
Y157480D03*
Y165354D03*
Y169291D03*
X880315Y145669D03*
Y149606D03*
Y153543D03*
Y157480D03*
Y161417D03*
Y165354D03*
Y169291D03*
Y173228D03*
X884252Y145669D03*
Y149606D03*
Y153543D03*
Y157480D03*
Y161417D03*
Y165354D03*
Y169291D03*
Y173228D03*
X888189Y145669D03*
Y149606D03*
Y153543D03*
Y157480D03*
Y161417D03*
Y165354D03*
Y169291D03*
Y173228D03*
X892126Y145669D03*
Y149606D03*
Y153543D03*
Y157480D03*
Y161417D03*
Y165354D03*
Y169291D03*
Y173228D03*
X896063Y145669D03*
Y149606D03*
Y153543D03*
Y157480D03*
Y161417D03*
Y165354D03*
Y169291D03*
Y173228D03*
X900000Y145669D03*
Y149606D03*
Y153543D03*
Y157480D03*
Y161417D03*
Y165354D03*
Y169291D03*
Y173228D03*
X903937Y145669D03*
Y149606D03*
Y153543D03*
Y157480D03*
Y161417D03*
Y165354D03*
Y169291D03*
Y173228D03*
X907874Y145669D03*
Y149606D03*
Y153543D03*
Y157480D03*
Y161417D03*
Y165354D03*
Y169291D03*
Y173228D03*
X876378Y177165D03*
Y185039D03*
Y192913D03*
Y200787D03*
Y204724D03*
X880315Y177165D03*
Y181102D03*
Y185039D03*
Y188976D03*
Y192913D03*
Y196850D03*
Y200787D03*
Y204724D03*
Y208661D03*
X884252Y177165D03*
Y181102D03*
Y185039D03*
Y188976D03*
Y192913D03*
Y196850D03*
Y200787D03*
Y204724D03*
Y208661D03*
X888189Y177165D03*
Y181102D03*
Y185039D03*
Y188976D03*
Y192913D03*
Y196850D03*
Y200787D03*
Y204724D03*
Y208661D03*
X892126Y177165D03*
Y181102D03*
Y185039D03*
Y188976D03*
Y192913D03*
Y196850D03*
Y200787D03*
Y204724D03*
Y208661D03*
X896063Y177165D03*
Y181102D03*
Y185039D03*
Y188976D03*
Y192913D03*
Y196850D03*
Y200787D03*
Y204724D03*
Y208661D03*
X900000Y177165D03*
Y181102D03*
Y185039D03*
Y188976D03*
Y192913D03*
Y196850D03*
Y200787D03*
Y204724D03*
Y208661D03*
X903937Y177165D03*
Y181102D03*
Y185039D03*
Y188976D03*
Y192913D03*
Y196850D03*
Y200787D03*
Y204724D03*
Y208661D03*
X907874Y177165D03*
Y181102D03*
Y185039D03*
Y188976D03*
Y192913D03*
Y196850D03*
Y200787D03*
Y204724D03*
Y208661D03*
X876378Y212598D03*
Y220472D03*
Y228346D03*
Y236220D03*
Y240157D03*
X880315Y212598D03*
Y216535D03*
Y220472D03*
Y224409D03*
Y228346D03*
Y232283D03*
Y236220D03*
Y240157D03*
X884252Y212598D03*
Y216535D03*
Y220472D03*
Y224409D03*
Y228346D03*
Y232283D03*
Y236220D03*
Y240157D03*
X888189Y212598D03*
Y216535D03*
Y220472D03*
Y224409D03*
Y228346D03*
Y232283D03*
Y236220D03*
Y240157D03*
X892126Y212598D03*
Y216535D03*
Y220472D03*
Y224409D03*
Y228346D03*
Y232283D03*
Y236220D03*
Y240157D03*
X896063Y212598D03*
Y216535D03*
Y220472D03*
Y224409D03*
Y228346D03*
Y232283D03*
Y236220D03*
Y240157D03*
X900000Y212598D03*
Y216535D03*
Y220472D03*
Y224409D03*
Y228346D03*
Y232283D03*
Y236220D03*
Y240157D03*
X903937Y212598D03*
Y216535D03*
Y220472D03*
Y224409D03*
Y228346D03*
Y232283D03*
Y236220D03*
Y240157D03*
X907874Y212598D03*
Y216535D03*
Y220472D03*
Y224409D03*
Y228346D03*
Y232283D03*
Y236220D03*
Y240157D03*
X876378Y244094D03*
Y248031D03*
X880315Y244094D03*
Y248031D03*
X884252Y244094D03*
Y248031D03*
X888189Y244094D03*
Y248031D03*
Y251968D03*
Y255905D03*
Y259842D03*
X892126Y244094D03*
Y248031D03*
Y251968D03*
Y255905D03*
X896063Y244094D03*
Y248031D03*
Y251968D03*
Y255905D03*
Y259842D03*
X900000Y244094D03*
Y248031D03*
Y251968D03*
Y255905D03*
X903937Y244094D03*
Y248031D03*
Y251968D03*
Y255905D03*
Y259842D03*
X907874Y244094D03*
Y248031D03*
Y251968D03*
Y255905D03*
X911811Y122047D03*
Y125984D03*
Y129921D03*
Y133858D03*
Y137795D03*
Y141732D03*
X915748Y118110D03*
Y122047D03*
Y125984D03*
Y129921D03*
Y133858D03*
Y137795D03*
Y141732D03*
X919685Y122047D03*
Y125984D03*
Y129921D03*
Y133858D03*
Y137795D03*
Y141732D03*
X923622Y118110D03*
Y122047D03*
Y125984D03*
Y129921D03*
Y133858D03*
Y137795D03*
Y141732D03*
X927559Y122047D03*
Y125984D03*
Y129921D03*
Y133858D03*
Y137795D03*
Y141732D03*
X931496Y118110D03*
Y122047D03*
Y125984D03*
Y129921D03*
Y133858D03*
Y137795D03*
Y141732D03*
X935433Y122047D03*
Y125984D03*
Y129921D03*
Y133858D03*
Y137795D03*
Y141732D03*
X939370Y118110D03*
Y122047D03*
Y125984D03*
Y129921D03*
Y133858D03*
Y137795D03*
Y141732D03*
X911811Y145669D03*
Y149606D03*
Y153543D03*
Y157480D03*
Y161417D03*
Y165354D03*
Y169291D03*
Y173228D03*
X915748Y145669D03*
Y149606D03*
Y153543D03*
Y157480D03*
Y161417D03*
Y165354D03*
Y169291D03*
Y173228D03*
X919685Y145669D03*
Y149606D03*
Y153543D03*
Y157480D03*
Y161417D03*
Y165354D03*
Y169291D03*
Y173228D03*
X923622Y145669D03*
Y149606D03*
Y153543D03*
Y157480D03*
Y161417D03*
Y165354D03*
Y169291D03*
Y173228D03*
X927559Y145669D03*
Y149606D03*
Y153543D03*
Y157480D03*
Y161417D03*
Y165354D03*
Y169291D03*
Y173228D03*
X931496Y145669D03*
Y149606D03*
Y153543D03*
Y157480D03*
Y161417D03*
Y165354D03*
Y169291D03*
Y173228D03*
X935433Y145669D03*
Y149606D03*
Y153543D03*
Y157480D03*
Y161417D03*
Y165354D03*
Y169291D03*
Y173228D03*
X939370Y145669D03*
Y149606D03*
Y153543D03*
Y157480D03*
Y161417D03*
Y165354D03*
Y169291D03*
Y173228D03*
X911811Y177165D03*
Y181102D03*
Y185039D03*
Y188976D03*
Y192913D03*
Y196850D03*
Y200787D03*
Y204724D03*
Y208661D03*
X915748Y177165D03*
Y181102D03*
Y185039D03*
Y188976D03*
Y192913D03*
Y196850D03*
Y200787D03*
Y204724D03*
Y208661D03*
X919685Y177165D03*
Y181102D03*
Y185039D03*
Y188976D03*
Y192913D03*
Y196850D03*
Y200787D03*
Y204724D03*
Y208661D03*
X923622Y177165D03*
Y181102D03*
Y185039D03*
Y188976D03*
Y192913D03*
Y196850D03*
Y200787D03*
Y204724D03*
Y208661D03*
X927559Y177165D03*
Y181102D03*
Y185039D03*
Y188976D03*
Y192913D03*
Y196850D03*
Y200787D03*
Y204724D03*
Y208661D03*
X931496Y177165D03*
Y181102D03*
Y185039D03*
Y188976D03*
Y192913D03*
Y196850D03*
Y200787D03*
Y204724D03*
Y208661D03*
X935433Y177165D03*
Y181102D03*
Y185039D03*
Y188976D03*
Y192913D03*
Y196850D03*
Y200787D03*
Y204724D03*
Y208661D03*
X939370Y177165D03*
Y181102D03*
Y185039D03*
Y188976D03*
Y192913D03*
Y196850D03*
Y200787D03*
Y204724D03*
Y208661D03*
X911811Y212598D03*
Y216535D03*
Y220472D03*
Y224409D03*
Y228346D03*
Y232283D03*
Y236220D03*
Y240157D03*
X915748Y212598D03*
Y216535D03*
Y220472D03*
Y224409D03*
Y228346D03*
Y232283D03*
Y236220D03*
Y240157D03*
X919685Y212598D03*
Y216535D03*
Y220472D03*
Y224409D03*
Y228346D03*
Y232283D03*
Y236220D03*
Y240157D03*
X923622Y212598D03*
Y216535D03*
Y220472D03*
Y224409D03*
Y228346D03*
Y232283D03*
Y236220D03*
Y240157D03*
X927559Y212598D03*
Y216535D03*
Y220472D03*
Y224409D03*
Y228346D03*
Y232283D03*
Y236220D03*
Y240157D03*
X931496Y212598D03*
Y216535D03*
Y220472D03*
Y224409D03*
Y228346D03*
Y232283D03*
Y236220D03*
Y240157D03*
X935433Y212598D03*
Y216535D03*
Y220472D03*
Y224409D03*
Y228346D03*
Y232283D03*
Y236220D03*
Y240157D03*
X939370Y212598D03*
Y216535D03*
Y220472D03*
Y224409D03*
Y228346D03*
Y232283D03*
Y236220D03*
Y240157D03*
X911811Y244094D03*
Y248031D03*
Y251968D03*
Y255905D03*
Y259842D03*
X915748Y244094D03*
Y248031D03*
Y251968D03*
Y255905D03*
Y259842D03*
X919685Y244094D03*
Y248031D03*
Y251968D03*
Y255905D03*
X923622Y244094D03*
Y248031D03*
Y251968D03*
Y255905D03*
Y259842D03*
X927559Y244094D03*
Y248031D03*
Y251968D03*
Y255905D03*
X931496Y244094D03*
Y248031D03*
Y251968D03*
Y255905D03*
Y259842D03*
X935433Y244094D03*
Y248031D03*
Y251968D03*
Y255905D03*
X939370Y244094D03*
Y248031D03*
Y251968D03*
Y255905D03*
Y259842D03*
X943307Y118110D03*
Y122047D03*
Y125984D03*
Y129921D03*
Y133858D03*
Y137795D03*
Y141732D03*
X947244Y118110D03*
Y122047D03*
Y125984D03*
Y129921D03*
Y133858D03*
Y137795D03*
Y141732D03*
X951181Y118110D03*
Y122047D03*
Y125984D03*
Y129921D03*
Y133858D03*
Y137795D03*
Y141732D03*
X955118Y118110D03*
Y122047D03*
Y125984D03*
Y129921D03*
Y133858D03*
Y137795D03*
Y141732D03*
X959055Y122047D03*
Y125984D03*
Y129921D03*
Y133858D03*
Y137795D03*
Y141732D03*
X962992Y118110D03*
Y122047D03*
Y125984D03*
Y129921D03*
Y133858D03*
Y137795D03*
Y141732D03*
X966929Y122047D03*
Y125984D03*
Y129921D03*
Y133858D03*
Y137795D03*
Y141732D03*
X970866Y118110D03*
Y122047D03*
Y125984D03*
Y129921D03*
Y133858D03*
Y137795D03*
Y141732D03*
X974803Y122047D03*
Y125984D03*
Y129921D03*
Y133858D03*
Y137795D03*
Y141732D03*
X943307Y145669D03*
Y149606D03*
Y153543D03*
Y157480D03*
Y161417D03*
Y165354D03*
Y169291D03*
Y173228D03*
X947244Y145669D03*
Y149606D03*
Y153543D03*
Y157480D03*
Y161417D03*
Y165354D03*
Y169291D03*
Y173228D03*
X951181Y145669D03*
Y149606D03*
Y153543D03*
Y157480D03*
Y161417D03*
Y165354D03*
Y169291D03*
Y173228D03*
X955118Y145669D03*
Y149606D03*
Y153543D03*
Y157480D03*
Y161417D03*
Y165354D03*
Y169291D03*
Y173228D03*
X959055Y145669D03*
Y149606D03*
Y153543D03*
Y157480D03*
Y161417D03*
Y165354D03*
Y169291D03*
Y173228D03*
X962992Y145669D03*
Y149606D03*
Y153543D03*
Y157480D03*
Y161417D03*
Y165354D03*
Y169291D03*
Y173228D03*
X966929Y145669D03*
Y149606D03*
Y153543D03*
Y157480D03*
Y161417D03*
Y165354D03*
Y169291D03*
Y173228D03*
X970866Y145669D03*
Y149606D03*
Y153543D03*
Y157480D03*
Y161417D03*
Y165354D03*
Y169291D03*
Y173228D03*
X974803Y145669D03*
Y149606D03*
Y153543D03*
Y157480D03*
Y161417D03*
Y165354D03*
Y169291D03*
Y173228D03*
X943307Y177165D03*
Y181102D03*
Y185039D03*
Y188976D03*
Y192913D03*
Y196850D03*
Y200787D03*
Y204724D03*
Y208661D03*
X947244Y177165D03*
Y181102D03*
Y185039D03*
Y188976D03*
Y192913D03*
Y196850D03*
Y200787D03*
Y204724D03*
Y208661D03*
X951181Y177165D03*
Y181102D03*
Y185039D03*
Y188976D03*
Y192913D03*
Y196850D03*
Y200787D03*
Y204724D03*
Y208661D03*
X955118Y177165D03*
Y181102D03*
Y185039D03*
Y188976D03*
Y192913D03*
Y196850D03*
Y200787D03*
Y204724D03*
Y208661D03*
X959055Y177165D03*
Y181102D03*
Y185039D03*
Y188976D03*
Y192913D03*
Y196850D03*
Y200787D03*
Y204724D03*
Y208661D03*
X962992Y177165D03*
Y181102D03*
Y185039D03*
Y188976D03*
Y192913D03*
Y196850D03*
Y200787D03*
Y204724D03*
Y208661D03*
X966929Y177165D03*
Y181102D03*
Y185039D03*
Y188976D03*
Y192913D03*
Y196850D03*
Y200787D03*
Y204724D03*
Y208661D03*
X970866Y177165D03*
Y181102D03*
Y185039D03*
Y188976D03*
Y192913D03*
Y196850D03*
Y200787D03*
Y204724D03*
Y208661D03*
X974803Y177165D03*
Y181102D03*
Y185039D03*
Y188976D03*
Y192913D03*
Y196850D03*
Y200787D03*
Y204724D03*
Y208661D03*
X943307Y212598D03*
Y216535D03*
Y220472D03*
Y224409D03*
Y228346D03*
Y232283D03*
Y236220D03*
Y240157D03*
X947244Y212598D03*
Y216535D03*
Y220472D03*
Y224409D03*
Y228346D03*
Y232283D03*
Y236220D03*
Y240157D03*
X951181Y212598D03*
Y216535D03*
Y220472D03*
Y224409D03*
Y228346D03*
Y232283D03*
Y236220D03*
Y240157D03*
X955118Y212598D03*
Y216535D03*
Y220472D03*
Y224409D03*
Y228346D03*
Y232283D03*
Y236220D03*
Y240157D03*
X959055Y212598D03*
Y216535D03*
Y220472D03*
Y224409D03*
Y228346D03*
Y232283D03*
Y236220D03*
Y240157D03*
X962992Y212598D03*
Y216535D03*
Y220472D03*
Y224409D03*
Y228346D03*
Y232283D03*
Y236220D03*
Y240157D03*
X966929Y212598D03*
Y216535D03*
Y220472D03*
Y224409D03*
Y228346D03*
Y232283D03*
Y236220D03*
Y240157D03*
X970866Y212598D03*
Y216535D03*
Y220472D03*
Y224409D03*
Y228346D03*
Y232283D03*
Y236220D03*
Y240157D03*
X974803Y212598D03*
Y216535D03*
Y220472D03*
Y224409D03*
Y228346D03*
Y232283D03*
Y236220D03*
Y240157D03*
X943307Y244094D03*
Y248031D03*
Y251968D03*
Y255905D03*
X947244Y244094D03*
Y248031D03*
Y251968D03*
Y255905D03*
Y259842D03*
X951181Y244094D03*
Y248031D03*
Y251968D03*
Y255905D03*
X955118Y244094D03*
Y248031D03*
Y251968D03*
Y255905D03*
Y259842D03*
X959055Y244094D03*
Y248031D03*
Y251968D03*
Y255905D03*
X962992Y244094D03*
Y248031D03*
Y251968D03*
Y255905D03*
Y259842D03*
X966929Y244094D03*
Y248031D03*
Y251968D03*
Y255905D03*
X970866Y244094D03*
Y248031D03*
Y251968D03*
Y255905D03*
Y259842D03*
X974803Y244094D03*
Y248031D03*
Y251968D03*
Y255905D03*
X978740Y118110D03*
Y122047D03*
Y125984D03*
Y129921D03*
Y133858D03*
Y137795D03*
Y141732D03*
X982677Y122047D03*
Y125984D03*
Y129921D03*
Y133858D03*
Y137795D03*
Y141732D03*
X986614Y118110D03*
Y122047D03*
Y125984D03*
Y129921D03*
Y133858D03*
Y137795D03*
Y141732D03*
X990551Y118110D03*
Y122047D03*
Y125984D03*
Y129921D03*
Y133858D03*
Y137795D03*
Y141732D03*
X994488Y122047D03*
Y125984D03*
Y129921D03*
Y133858D03*
Y137795D03*
Y141732D03*
X998425Y118110D03*
Y122047D03*
Y125984D03*
Y129921D03*
Y133858D03*
Y137795D03*
Y141732D03*
X1002362Y122047D03*
Y125984D03*
Y129921D03*
Y133858D03*
Y137795D03*
Y141732D03*
X1006299Y118110D03*
Y122047D03*
Y125984D03*
Y129921D03*
Y133858D03*
Y137795D03*
Y141732D03*
X978740Y145669D03*
Y149606D03*
Y153543D03*
Y157480D03*
Y161417D03*
Y165354D03*
Y169291D03*
Y173228D03*
X982677Y145669D03*
Y149606D03*
Y153543D03*
Y157480D03*
Y161417D03*
Y165354D03*
Y169291D03*
Y173228D03*
X986614Y145669D03*
Y149606D03*
Y153543D03*
Y157480D03*
Y161417D03*
Y165354D03*
Y169291D03*
Y173228D03*
X990551Y145669D03*
Y149606D03*
Y153543D03*
Y157480D03*
Y161417D03*
Y165354D03*
Y169291D03*
Y173228D03*
X994488Y145669D03*
Y149606D03*
Y153543D03*
Y157480D03*
Y161417D03*
Y165354D03*
Y169291D03*
Y173228D03*
X998425Y145669D03*
Y149606D03*
Y153543D03*
Y157480D03*
Y161417D03*
Y165354D03*
Y169291D03*
Y173228D03*
X1002362Y145669D03*
Y149606D03*
Y153543D03*
Y157480D03*
Y161417D03*
Y165354D03*
Y169291D03*
Y173228D03*
X1006299Y145669D03*
Y149606D03*
Y153543D03*
Y157480D03*
Y161417D03*
Y165354D03*
Y169291D03*
Y173228D03*
X978740Y177165D03*
Y181102D03*
Y185039D03*
Y188976D03*
Y192913D03*
Y196850D03*
Y200787D03*
Y204724D03*
Y208661D03*
X982677Y177165D03*
Y181102D03*
Y185039D03*
Y188976D03*
Y192913D03*
Y196850D03*
Y200787D03*
Y204724D03*
Y208661D03*
X986614Y177165D03*
Y181102D03*
Y185039D03*
Y188976D03*
Y192913D03*
Y196850D03*
Y200787D03*
Y204724D03*
Y208661D03*
X990551Y177165D03*
Y181102D03*
Y185039D03*
Y188976D03*
Y192913D03*
Y196850D03*
Y200787D03*
Y204724D03*
Y208661D03*
X994488Y177165D03*
Y181102D03*
Y185039D03*
Y188976D03*
Y192913D03*
Y196850D03*
Y200787D03*
Y204724D03*
Y208661D03*
X998425Y177165D03*
Y181102D03*
Y185039D03*
Y188976D03*
Y192913D03*
Y196850D03*
Y200787D03*
Y204724D03*
Y208661D03*
X1002362Y177165D03*
Y181102D03*
Y185039D03*
Y188976D03*
Y192913D03*
Y196850D03*
Y200787D03*
Y204724D03*
Y208661D03*
X1006299Y177165D03*
Y181102D03*
Y185039D03*
Y188976D03*
Y192913D03*
Y196850D03*
Y200787D03*
Y204724D03*
Y208661D03*
X978740Y212598D03*
Y216535D03*
Y220472D03*
Y224409D03*
Y228346D03*
Y232283D03*
Y236220D03*
Y240157D03*
X982677Y212598D03*
Y216535D03*
Y220472D03*
Y224409D03*
Y228346D03*
Y232283D03*
Y236220D03*
Y240157D03*
X986614Y212598D03*
Y216535D03*
Y220472D03*
Y224409D03*
Y228346D03*
Y232283D03*
Y236220D03*
Y240157D03*
X990551Y212598D03*
Y216535D03*
Y220472D03*
Y224409D03*
Y228346D03*
Y232283D03*
Y236220D03*
Y240157D03*
X994488Y212598D03*
Y216535D03*
Y220472D03*
Y224409D03*
Y228346D03*
Y232283D03*
Y236220D03*
Y240157D03*
X998425Y212598D03*
Y216535D03*
Y220472D03*
Y224409D03*
Y228346D03*
Y232283D03*
Y236220D03*
Y240157D03*
X1002362Y212598D03*
Y216535D03*
Y220472D03*
Y224409D03*
Y228346D03*
Y232283D03*
Y236220D03*
Y240157D03*
X1006299Y212598D03*
Y216535D03*
Y220472D03*
Y224409D03*
Y228346D03*
Y232283D03*
Y236220D03*
Y240157D03*
X978740Y244094D03*
Y248031D03*
Y251968D03*
Y255905D03*
Y259842D03*
X982677Y244094D03*
Y248031D03*
Y251968D03*
Y255905D03*
Y259842D03*
X986614Y244094D03*
Y248031D03*
Y251968D03*
Y255905D03*
X990551Y244094D03*
Y248031D03*
Y251968D03*
Y255905D03*
Y259842D03*
X994488Y244094D03*
Y248031D03*
Y251968D03*
Y255905D03*
X998425Y244094D03*
Y248031D03*
Y251968D03*
Y255905D03*
Y259842D03*
X1002362Y244094D03*
Y248031D03*
Y251968D03*
Y255905D03*
X1006299Y244094D03*
Y248031D03*
Y251968D03*
Y255905D03*
Y259842D03*
X1010236Y129921D03*
Y133858D03*
Y137795D03*
Y141732D03*
X1014173Y129921D03*
Y133858D03*
Y137795D03*
Y141732D03*
X1018110Y129921D03*
Y133858D03*
Y141732D03*
X1010236Y145669D03*
Y149606D03*
Y153543D03*
Y157480D03*
Y161417D03*
Y165354D03*
Y169291D03*
Y173228D03*
X1014173Y145669D03*
Y149606D03*
Y153543D03*
Y157480D03*
Y161417D03*
Y165354D03*
Y169291D03*
Y173228D03*
X1018110Y149606D03*
Y157480D03*
Y165354D03*
Y169291D03*
X1010236Y177165D03*
Y181102D03*
Y185039D03*
Y188976D03*
Y192913D03*
Y196850D03*
Y200787D03*
Y204724D03*
Y208661D03*
X1014173Y177165D03*
Y181102D03*
Y185039D03*
Y188976D03*
Y192913D03*
Y196850D03*
Y200787D03*
Y204724D03*
Y208661D03*
X1018110Y177165D03*
Y185039D03*
Y192913D03*
Y200787D03*
Y204724D03*
X1010236Y212598D03*
Y216535D03*
Y220472D03*
Y224409D03*
Y228346D03*
Y232283D03*
Y236220D03*
Y240157D03*
X1014173Y212598D03*
Y216535D03*
Y220472D03*
Y224409D03*
Y228346D03*
Y232283D03*
Y236220D03*
Y240157D03*
X1018110Y212598D03*
Y220472D03*
Y228346D03*
Y236220D03*
Y240157D03*
X1010236Y244094D03*
Y248031D03*
X1014173Y244094D03*
Y248031D03*
X1018110Y244094D03*
Y248031D03*
G54D37*
X4100Y865800D03*
X46678Y-681D03*
X50400Y826100D03*
X93450Y562220D03*
X107400Y119000D03*
X226500Y424700D03*
X854450Y99220D03*
X1037450Y272220D03*
X1374900Y761800D03*
X1383700Y138500D03*
X1396600Y862800D03*
G54D139*
X700939Y212618D03*
X738439D03*
G54D82*
X116948Y486948D03*
X120098D03*
X123247D03*
X116948Y483799D03*
X120098D03*
X123247D03*
X116948Y480649D03*
X120098D03*
X123247D03*
X116948Y546791D03*
X120098D03*
X123247D03*
X116948Y543641D03*
X120098D03*
X123247D03*
X116948Y540492D03*
X120098D03*
X123247D03*
X176791Y486948D03*
X179940D03*
X183090D03*
X176791Y483799D03*
X179940D03*
X183090D03*
X176791Y480649D03*
X179940D03*
X183090D03*
X176791Y546791D03*
X179940D03*
X183090D03*
X176791Y543641D03*
X179940D03*
X183090D03*
X176791Y540492D03*
X179940D03*
X183090D03*
G54D64*
X92990Y252362D03*
X116790D03*
X223500Y601500D03*
X906500Y316500D03*
X1301120Y173278D03*
Y183908D03*
G54D55*
G01X127746Y-260199D02*
X95746D01*
G01X127746Y-276199D02*
Y-356199D01*
G01D02*
X1310146D01*
G01X127746Y-311699D02*
X1310146D01*
G01X123746Y-260199D02*
G02I-12000J0D01*
G01X118596D02*
G02I-6850J0D01*
G01X111746Y-276199D02*
Y-244199D01*
G01X127746Y-276199D02*
X1310146D01*
G01X522646D02*
Y-356199D01*
G01X660146Y-276199D02*
Y-356199D01*
G01X775146Y-276199D02*
Y-356199D01*
G01X942646Y-276199D02*
Y-356199D01*
G01X1112646Y-276199D02*
Y-356199D01*
G01X1310146Y-276199D02*
Y-356199D01*
G01X1342146Y-260199D02*
X1310146D01*
G01X1338146D02*
G02I-12000J0D01*
G01X1332996D02*
G02I-6850J0D01*
G01X1326146Y-276199D02*
Y-244199D01*
X48000Y426000D03*
Y422500D03*
Y429500D03*
X59300Y734900D03*
X54300Y729900D03*
X49300Y734900D03*
X54300Y739900D03*
Y734900D03*
X71500Y297900D03*
X77100Y303800D03*
X65400D03*
X65500Y291900D03*
X77500D03*
X108200Y775800D03*
X112700Y775300D03*
Y770800D03*
X108200D03*
X103700D03*
Y775800D03*
Y766300D03*
X108200D03*
X112700D03*
X158170Y314302D03*
X162670D03*
X153670D03*
X156170Y318302D03*
X160670D03*
X140500Y390500D03*
X145500Y385500D03*
X143000Y388000D03*
X224500Y170500D03*
Y174700D03*
Y166300D03*
Y178900D03*
X223000Y184000D03*
Y188500D03*
X225000Y192500D03*
X229200D03*
X264500Y142750D03*
X259500Y138500D03*
X254500Y142750D03*
X259500Y143250D03*
Y147750D03*
Y160750D03*
Y156250D03*
X264397Y160977D03*
X264500Y157250D03*
Y153750D03*
Y150250D03*
Y146250D03*
X259500Y152000D03*
X254500Y161250D03*
Y157250D03*
Y153750D03*
Y150250D03*
Y146250D03*
X261500Y173500D03*
X253000Y166500D03*
X258700D03*
X262900D03*
X243000Y176500D03*
X243500Y166500D03*
Y162000D03*
Y157000D03*
X261500Y179000D03*
Y184500D03*
X261000Y190500D03*
X258225Y193963D03*
X266500Y184500D03*
Y190500D03*
X243000Y181000D03*
Y186000D03*
X239900Y600100D03*
X240000Y608600D03*
Y604400D03*
X259300Y632400D03*
Y639300D03*
Y635900D03*
X271000Y184500D03*
X329500Y192500D03*
X328000Y197400D03*
X334500Y197500D03*
Y192500D03*
X344000Y197500D03*
X339500D03*
X344000Y192500D03*
X339500D03*
X536081Y304376D03*
X536809Y298789D03*
X565063Y256608D03*
Y247608D03*
Y252108D03*
X560318Y267199D03*
Y272199D03*
X560418Y278299D03*
Y283799D03*
Y289299D03*
X560318Y295699D03*
X553563Y306108D03*
Y310608D03*
X557904Y327115D03*
X562123Y319158D03*
X553455Y314807D03*
X553463Y319108D03*
X557863D03*
X560531Y358080D03*
X564100Y358100D03*
X556500Y358000D03*
X597763Y242608D03*
X602763Y240858D03*
X597763Y231608D03*
Y235108D03*
Y239108D03*
X602763Y236608D03*
Y232108D03*
X597763Y246108D03*
Y250108D03*
X602763Y245108D03*
Y249608D03*
X605063Y257608D03*
X585515Y276459D03*
X583009Y264117D03*
X585351Y269292D03*
X587984Y246148D03*
X587980Y251975D03*
X589164Y264150D03*
X582738Y273300D03*
X587063Y257608D03*
X582976Y246148D03*
X583286Y251974D03*
X582682Y257614D03*
X589400Y308626D03*
X585737Y289608D03*
Y283108D03*
X582683Y279618D03*
X582411Y286589D03*
X582363Y293408D03*
X580563Y308608D03*
X583391Y298870D03*
X583282Y303091D03*
X607763Y242608D03*
Y231608D03*
Y235108D03*
Y239108D03*
X611563Y278108D03*
X607763Y246108D03*
Y250108D03*
X607563Y265608D03*
X607463Y270608D03*
X607563Y261108D03*
X609063Y255608D03*
X607563Y276108D03*
Y282108D03*
Y287608D03*
Y293608D03*
X607519Y299497D03*
X611563Y290108D03*
Y284608D03*
X633000Y356600D03*
Y360500D03*
Y353000D03*
X636500Y356500D03*
X629500D03*
X666593Y226677D03*
X662593Y223677D03*
X658093D03*
X670063Y274708D03*
X669633Y259148D03*
X672100Y299800D03*
X704537Y221492D03*
X678063Y238108D03*
X673063D03*
X672927Y219677D03*
X677927D03*
X686063Y230108D03*
X696800Y237900D03*
X682763Y238008D03*
X686063Y224608D03*
X703600Y233700D03*
X687253Y237878D03*
X691753D03*
X698300Y226500D03*
X693800D03*
X689623Y269648D03*
X694963Y269608D03*
X689723Y274748D03*
X694223D03*
X679723D03*
X684223D03*
X690233Y255748D03*
X695000Y255800D03*
X690133Y260348D03*
X694633D03*
X680133Y259148D03*
X684633D03*
X674563Y274708D03*
X674133Y259148D03*
X695963Y302308D03*
Y297808D03*
Y293308D03*
X690663Y287608D03*
Y292108D03*
X677000Y299900D03*
X682063Y299108D03*
X683800Y295000D03*
X684063Y285908D03*
Y290408D03*
X712337Y207792D03*
X712137Y213292D03*
Y219392D03*
X725300Y228700D03*
X730300D03*
X711300D03*
X716300D03*
X716900Y233800D03*
X721400D03*
X730400D03*
X725900D03*
X735400D03*
X707900D03*
X712400D03*
X738800Y272000D03*
Y265500D03*
Y258000D03*
Y251500D03*
X706800Y272500D03*
Y265500D03*
Y258000D03*
Y252000D03*
X715300Y272000D03*
Y265500D03*
Y258000D03*
Y251500D03*
X724300Y272000D03*
Y265500D03*
Y258000D03*
Y251500D03*
X732300Y272000D03*
Y265500D03*
Y258000D03*
Y251500D03*
X706800Y290700D03*
X718800Y291000D03*
X714300D03*
X707363Y298108D03*
X718863Y295908D03*
X714363D03*
X723300Y291000D03*
X732300D03*
X727800D03*
X723363Y295908D03*
X732363D03*
X727863D03*
X737300Y291000D03*
X876378Y122047D03*
Y125984D03*
X880315Y118110D03*
Y122047D03*
Y125984D03*
X884252Y122047D03*
Y125984D03*
X876378Y251968D03*
Y255905D03*
X880315Y251968D03*
Y255905D03*
Y259842D03*
X884252Y251968D03*
Y255905D03*
X921300Y74700D03*
X918100Y71900D03*
X929464Y49420D03*
X925022Y42909D03*
X929713Y44849D03*
X926500Y60050D03*
X930500Y57500D03*
X976066Y26581D03*
X971466Y26681D03*
X975086Y61900D03*
X970000Y61050D03*
X985880Y41686D03*
X980566Y26581D03*
X985880Y46086D03*
Y50586D03*
X1010236Y122047D03*
Y125984D03*
X1014173Y118110D03*
Y122047D03*
Y125984D03*
X1018110Y122047D03*
Y125984D03*
X1010236Y251968D03*
Y255905D03*
X1014173Y251968D03*
Y255905D03*
Y259842D03*
X1018110Y251968D03*
Y255905D03*
X1177600Y241200D03*
X1173400D03*
X1166400Y234300D03*
X1170600D03*
X1175700D03*
X1171300Y215700D03*
X1166300D03*
X1175999D03*
X1177200Y248200D03*
X1173000D03*
X1177300Y254400D03*
X1173100D03*
X1176300Y261500D03*
X1171200D03*
X1167000D03*
X1168000Y280000D03*
X1173000D03*
X1177500D03*
X1203100Y241100D03*
X1198900D03*
X1207900D03*
X1182400Y241200D03*
X1197900Y234300D03*
X1207400D03*
X1203200D03*
X1179900D03*
X1188900D03*
X1184700D03*
X1193700D03*
X1190300Y215700D03*
X1185300D03*
X1208800D03*
X1203800D03*
X1180601D03*
X1199300D03*
X1194500D03*
X1182000Y248200D03*
X1202600Y254100D03*
X1198400D03*
X1207400D03*
X1202500Y247500D03*
X1198300D03*
X1207300D03*
X1182100Y254400D03*
X1203800Y261500D03*
X1208000D03*
X1194300D03*
X1198500D03*
X1185300D03*
X1189500D03*
X1180500D03*
X1187000Y280000D03*
X1192000D03*
X1205500D03*
X1210500D03*
X1182500D03*
X1201000D03*
X1196200D03*
X1229000Y210500D03*
X1242500Y209000D03*
X1232000Y194500D03*
X1237000D03*
X1226500Y201500D03*
Y194500D03*
X1244500D03*
X1212900Y234300D03*
X1214800Y215700D03*
X1233900Y240700D03*
X1239900D03*
X1244900D03*
X1228900D03*
X1228500Y235000D03*
X1234000D03*
X1240000D03*
X1245000D03*
X1214000Y261500D03*
X1233800Y246600D03*
X1239800D03*
X1244800D03*
X1228800D03*
X1229000Y252000D03*
X1245000D03*
X1240000D03*
X1234000D03*
X1227000Y279000D03*
X1242000D03*
X1232000Y292000D03*
X1237000D03*
X1227000Y285500D03*
X1244500Y292000D03*
X1247500Y209000D03*
X1252500Y194500D03*
X1263000Y210307D03*
X1257500Y194500D03*
X1263000Y202000D03*
X1262500Y194500D03*
X1255900Y240700D03*
X1249900D03*
X1262500Y235000D03*
X1250000D03*
X1256000D03*
X1255800Y246600D03*
X1249800D03*
X1262000Y252000D03*
X1256000D03*
X1250000D03*
X1247000Y279000D03*
X1262500Y279500D03*
X1252000Y292000D03*
X1257000D03*
X1262500Y286000D03*
X1327782Y192579D03*
Y200579D03*
Y207579D03*
X1328411Y237679D03*
X1327782Y215579D03*
Y221579D03*
X1327841Y228639D03*
X1332683Y240409D03*
X1328356Y242091D03*
X1328317Y246291D03*
X1332683Y244609D03*
Y248809D03*
X1337000Y263250D03*
X1332000Y261500D03*
Y265000D03*
Y268500D03*
Y272500D03*
Y257500D03*
Y254000D03*
X1342000D03*
Y257500D03*
Y261500D03*
Y265000D03*
Y268500D03*
Y272500D03*
X1337000Y267500D03*
Y272000D03*
Y259000D03*
Y254500D03*
X1326250Y669550D03*
X1366672Y210312D03*
X1360844Y210366D03*
X1355944Y210313D03*
X1351525Y207104D03*
X1351545Y202879D03*
Y198575D03*
X1378115Y189144D03*
X1374000Y192500D03*
Y188300D03*
Y196700D03*
X1378500Y198000D03*
X1378115Y193344D03*
X1375196Y217203D03*
X1367042Y223895D03*
X1375359Y230110D03*
X1372000Y240500D03*
X1351777Y227823D03*
X1360644Y223881D03*
X1350987Y236754D03*
X1351668Y232125D03*
X1355644Y223881D03*
X1351899Y219598D03*
X1351954Y215268D03*
X1354989Y239016D03*
X1350950Y241000D03*
X1349639Y211374D03*
X1349298Y223737D03*
X1372000Y245300D03*
Y249500D03*
X1355050Y247300D03*
X1350950Y246100D03*
X1382500Y193500D03*
Y188000D03*
G54D65*
X71500Y297900D03*
G54D92*
X141060Y243523D03*
X152028D03*
X140907Y255980D03*
X151875D03*
X566079Y264008D03*
Y276308D03*
Y300908D03*
Y288608D03*
X591079Y274408D03*
X602047D03*
X577047Y264008D03*
Y276308D03*
X591079Y299008D03*
X602047D03*
X591079Y286708D03*
X602047D03*
X577047Y300908D03*
Y288608D03*
X1334016Y192500D03*
X1344984D03*
X1334016Y205000D03*
X1344984D03*
X1334016Y230000D03*
X1344984D03*
X1334016Y217500D03*
X1344984D03*
X1369484Y203500D03*
X1358516D03*
X1369484Y217000D03*
X1358516D03*
X1369484Y230500D03*
X1358516D03*
G54D38*
X42587Y151614D03*
X80579D03*
G54D74*
X69700Y695200D03*
Y706200D03*
X129189Y324436D03*
Y335436D03*
X216469Y168525D03*
Y179525D03*
G54D83*
X125740Y721650D03*
X123180D03*
X120620D03*
X118060D03*
Y737950D03*
X120620D03*
X123180D03*
X125740D03*
G54D47*
X56736Y279983D03*
Y315817D03*
X86264Y279983D03*
Y315817D03*
G54D56*
X37940Y478700D03*
X40500D03*
X43060D03*
X37940Y471300D03*
X40500D03*
X43060D03*
X58060Y488800D03*
X55500D03*
X52940D03*
X58060Y496200D03*
X55500D03*
X52940D03*
X266540Y472600D03*
Y480000D03*
X271660Y472600D03*
X269100D03*
X271660Y480000D03*
X269100D03*
G54D158*
X1356988Y55905D03*
G54D29*
X25500Y420000D03*
X20025Y435203D03*
X29400Y738500D03*
X24000Y751200D03*
X46000Y292100D03*
X45882Y287141D03*
X41300Y307200D03*
X62900Y322300D03*
X56500Y372900D03*
X34866Y390400D03*
X64800Y383400D03*
X60500Y439500D03*
X47500Y414000D03*
X60500Y417500D03*
X49000Y469400D03*
X59000Y454500D03*
X60810Y478441D03*
X31562Y465195D03*
X44000Y466500D03*
X31700Y481100D03*
X43046Y497465D03*
X59587Y511198D03*
X42534Y490525D03*
X63370Y498214D03*
X44500Y484000D03*
X52000Y501500D03*
Y484000D03*
X39616Y532255D03*
X64500Y615500D03*
X32498Y682487D03*
X61505Y689980D03*
X34831Y727839D03*
X34300Y732900D03*
X48700Y718195D03*
X35300Y738400D03*
X53700Y717250D03*
X42600Y718000D03*
X34800Y721900D03*
X37800Y745400D03*
X40200Y756200D03*
X35000Y756400D03*
X56100Y755900D03*
X50900Y756000D03*
X64400Y751800D03*
X45400Y756200D03*
X61300D03*
X90100Y266400D03*
X83300Y266800D03*
X75800Y269600D03*
X70000Y273000D03*
X80358Y274360D03*
X96677Y285294D03*
X94700Y335600D03*
X91300Y331600D03*
X96107Y324781D03*
X97838Y311989D03*
X96500Y316900D03*
X98400Y332400D03*
X85800Y355000D03*
X90093Y365200D03*
X67000Y377500D03*
X65965Y362838D03*
X84400Y406500D03*
X93314Y466166D03*
X88500Y509613D03*
X66473Y511404D03*
X73787Y522705D03*
X88727Y547047D03*
X88000Y538500D03*
X93100Y543638D03*
X71540Y518238D03*
X83600Y525700D03*
X81523Y521151D03*
X66494Y556916D03*
X88271Y552998D03*
X98008Y548438D03*
X96537Y555253D03*
X93400Y551200D03*
X65780Y586777D03*
X67508Y608289D03*
X83562Y610519D03*
X92000Y605500D03*
X78200Y646000D03*
X89600Y622600D03*
X73717Y632517D03*
X84000Y615500D03*
X85500Y706800D03*
X70700Y714000D03*
X85000Y714900D03*
X73800Y749600D03*
X71000Y719200D03*
X89600Y727900D03*
X73400Y741700D03*
X73900Y755200D03*
X111319Y195688D03*
X105300Y207900D03*
X111050Y207700D03*
X116300Y218100D03*
X128015Y219803D03*
X100688Y224517D03*
X107300Y272700D03*
X104000Y286200D03*
X124300Y305300D03*
X108385Y327857D03*
X131500Y340800D03*
X122963Y377696D03*
X119830Y348670D03*
X109285Y352411D03*
X130280Y389720D03*
X129694Y379247D03*
X112250Y385000D03*
X100400Y392184D03*
X130000Y397000D03*
X127633Y441705D03*
X131355Y437004D03*
X116300Y436400D03*
X120500Y461000D03*
X125500Y466000D03*
X128500Y456000D03*
X120680Y466020D03*
X102032Y475274D03*
X100000Y462700D03*
X115673Y464911D03*
X106983Y465035D03*
X111421Y467542D03*
X129076Y462500D03*
X107000Y472700D03*
X122406Y447830D03*
X102000Y497700D03*
X105045Y505292D03*
X107423Y500672D03*
X106258Y480600D03*
X99800Y511851D03*
X106000Y511600D03*
X99820Y505670D03*
X103313Y531239D03*
X99829Y527520D03*
X103100Y517400D03*
X103289Y523893D03*
X99476Y534446D03*
X103300Y537800D03*
X99164Y540611D03*
X103000Y555500D03*
X131500Y584000D03*
X104000Y627000D03*
X102020Y633720D03*
X119650Y707800D03*
X101800Y737200D03*
X102100Y723300D03*
X124800Y745300D03*
X120500Y752100D03*
X118600Y762500D03*
X98800Y764900D03*
X125900Y785000D03*
X119800Y813700D03*
X109500Y836500D03*
X162500Y222000D03*
X144300Y235400D03*
X137200Y302300D03*
X145300Y302200D03*
X136257Y316125D03*
X145168Y317749D03*
X137768Y322641D03*
X145965Y374500D03*
X160850Y375200D03*
X138905Y368565D03*
X148900Y363200D03*
X160303Y365303D03*
X151760Y372214D03*
X157065Y395331D03*
X160204Y384199D03*
X137778Y401708D03*
X161800Y389700D03*
X132778Y401706D03*
X134768Y429438D03*
X133812Y414712D03*
X143073Y424833D03*
X164222Y457919D03*
X134090Y465780D03*
X138930Y465660D03*
X141500Y461400D03*
X158790Y458450D03*
X160300Y465900D03*
X164268Y462983D03*
X154700Y461100D03*
X154500Y466000D03*
X150174Y458541D03*
X149461Y466837D03*
X144520Y466070D03*
X163225Y720683D03*
X139642Y736317D03*
X139480Y724027D03*
X149241Y740242D03*
X156126Y775783D03*
X163600Y757500D03*
X156400Y812800D03*
X142492Y795526D03*
X166890Y237540D03*
X182604Y442854D03*
X192173Y466075D03*
X179599Y457479D03*
X170192Y465776D03*
X175000Y466000D03*
X177377Y461749D03*
X180000Y466000D03*
X168320Y455278D03*
X185200Y466000D03*
X198274Y473078D03*
X199510Y465568D03*
X197228Y478071D03*
X189275Y470882D03*
X169399Y470740D03*
X199829Y485947D03*
X198279Y496230D03*
X198223Y509744D03*
X197126Y490845D03*
X198803Y501591D03*
X198000Y529500D03*
Y534500D03*
Y523000D03*
X196882Y542190D03*
X176500Y571500D03*
X174500Y561500D03*
X178500Y576376D03*
X174500Y566500D03*
X193610Y578880D03*
X175360Y580890D03*
X177187Y586239D03*
X187750Y584750D03*
X187500Y596000D03*
X195788Y696965D03*
X175505Y720797D03*
X195900Y733400D03*
X181873Y716530D03*
X189913Y736842D03*
X169029Y775496D03*
X195489Y752261D03*
X175300Y757500D03*
X182092Y771758D03*
X168100Y812800D03*
X195900Y789200D03*
X177092Y800861D03*
X231270Y140880D03*
X203740Y144334D03*
X214145Y147841D03*
X212000Y158300D03*
X205601Y426212D03*
X217998Y424771D03*
X202270Y438448D03*
X202652Y432259D03*
X220969Y431372D03*
X204700Y479804D03*
X204198Y474804D03*
X204500Y490000D03*
X202064Y512946D03*
X221152Y499246D03*
X203000Y534500D03*
X200217Y517593D03*
X217163Y523586D03*
X233101Y526064D03*
X204200Y522600D03*
X203314Y527894D03*
X208500Y563500D03*
X200000Y550424D03*
X202610Y563580D03*
X230856Y566468D03*
X204100Y600100D03*
X230250Y593750D03*
Y582400D03*
X207977Y696708D03*
X221200Y712250D03*
X207600Y733500D03*
X207931Y752312D03*
X218080Y771407D03*
X207600Y789200D03*
X242634Y134760D03*
X248992Y130867D03*
X233770Y152909D03*
X263068Y328619D03*
X252250Y343500D03*
X262604Y350015D03*
X247901Y422389D03*
X241800Y426300D03*
X266756Y431549D03*
X261349Y450988D03*
X249311Y450950D03*
X257000Y473400D03*
X265800Y467660D03*
Y485000D03*
X249601Y514174D03*
X249674Y532413D03*
X237779Y528680D03*
X235291Y521326D03*
X257000Y585500D03*
X248100Y622000D03*
X245050Y647100D03*
X243000Y737500D03*
X240275Y731000D03*
X246000Y745500D03*
X278909Y141324D03*
X280050Y149350D03*
X288000Y193000D03*
X299296Y327204D03*
X300300Y340501D03*
X274702Y365240D03*
X296940Y458370D03*
X296000Y497500D03*
X278100Y482000D03*
X293000Y625700D03*
X282500Y647700D03*
X270700Y627300D03*
X270800Y652900D03*
X280498Y726806D03*
X292831Y729494D03*
X279500Y764500D03*
X274406Y763500D03*
X273700Y752000D03*
X296500Y763000D03*
X290400Y763672D03*
X296872Y821628D03*
X295592Y828408D03*
X329894Y334794D03*
X329000Y320600D03*
X312430Y333540D03*
X304100Y336301D03*
X314485Y352315D03*
X328000Y663000D03*
X304416Y728698D03*
X310622Y760126D03*
X307000Y764000D03*
X303266Y825234D03*
X356361Y158609D03*
X351605Y334920D03*
X353000Y320300D03*
X354500Y325200D03*
X339149Y315170D03*
X344836Y314844D03*
X461900Y73800D03*
X455300Y90600D03*
X464692Y114063D03*
X455328Y159738D03*
X458029Y380305D03*
X465600Y428000D03*
X456100Y727000D03*
X486750Y31020D03*
X486979Y8837D03*
X486760Y54580D03*
X470200Y73800D03*
X478400D03*
X486764Y78077D03*
X474362Y130750D03*
X481800Y131719D03*
X488838Y140700D03*
X475567Y136564D03*
X475089Y114652D03*
X470047Y113969D03*
X497530Y144850D03*
X481801Y329085D03*
X488109Y332641D03*
X488009Y340441D03*
X484695Y360571D03*
X471852Y360377D03*
X484300Y397550D03*
X472600D03*
X494908Y379870D03*
X484830Y780711D03*
X493408Y778813D03*
X502044Y765135D03*
X493255Y816854D03*
X488255Y816894D03*
X487000Y801500D03*
X527293Y345998D03*
X520672Y345868D03*
X509246Y781700D03*
X519458Y779247D03*
X509855Y814998D03*
X520781Y816463D03*
X503745Y815682D03*
X534543Y829543D03*
X532217Y839013D03*
X561600Y154800D03*
X558100Y158600D03*
X538500Y154900D03*
X554074Y291069D03*
X551926Y295585D03*
X549000Y318500D03*
X565900Y339000D03*
X541400Y368580D03*
X548928Y347157D03*
X554500Y380500D03*
X540200Y837200D03*
X591571Y206500D03*
X573151Y211067D03*
X584522Y240830D03*
X571600Y324400D03*
X573500Y381000D03*
X637063Y229408D03*
X632449Y224622D03*
X638063Y290608D03*
X632000Y329100D03*
X620200Y335900D03*
X626260Y341091D03*
X608090Y338070D03*
X632750Y341033D03*
X632600Y372042D03*
X632000Y384100D03*
X637000D03*
X626900Y390900D03*
X613400Y387000D03*
X636150Y400100D03*
X628148Y805648D03*
X614444Y800544D03*
X638470Y807070D03*
X671000Y215000D03*
X660100Y344600D03*
X647621Y340950D03*
X660500Y367100D03*
Y362300D03*
Y372100D03*
X648500Y372000D03*
X642000Y384100D03*
X682000Y174300D03*
X674100Y191500D03*
X688200Y191200D03*
X685000Y215000D03*
X694500Y366000D03*
X713332Y1831D03*
X736317Y35906D03*
X732837Y9562D03*
X723740Y9594D03*
X718343Y10856D03*
X717325Y28240D03*
X738220Y68350D03*
X718500Y68500D03*
X756565Y30918D03*
X763400Y35200D03*
X760084Y53800D03*
X758000Y68500D03*
X742367Y57852D03*
X763147Y65169D03*
X767450Y68465D03*
X766000Y85700D03*
X766683Y99583D03*
X766000Y94400D03*
X768700Y139100D03*
X767600Y117400D03*
X751300Y115000D03*
X745000Y733500D03*
X774392Y69785D03*
X779752Y70067D03*
X773617Y104731D03*
X802600Y89500D03*
X786200Y136200D03*
X805247Y123218D03*
X815200Y7500D03*
X813214Y38497D03*
X824118Y55116D03*
X839289Y68301D03*
X835492Y72992D03*
X835500Y100500D03*
X816600Y83025D03*
X822035Y130312D03*
X811202Y139324D03*
X807900Y114800D03*
X807801Y127889D03*
X833086Y743052D03*
X830569Y751931D03*
X828394Y760106D03*
X865500Y-824D03*
X854453Y3932D03*
X868819Y27276D03*
X869250Y39909D03*
X869195Y34816D03*
X869250Y45400D03*
X863500Y59400D03*
X848781Y64281D03*
X844212Y69179D03*
X842300Y63300D03*
X856000Y62500D03*
X842707Y75879D03*
X861310Y122608D03*
X846730Y123128D03*
X854510Y122640D03*
X847710Y110570D03*
X867000Y357000D03*
X854749Y692148D03*
X864000Y758000D03*
X855292Y782500D03*
X872244Y755738D03*
X863374Y792846D03*
X858000Y794000D03*
X873700Y792100D03*
X901000Y34000D03*
Y29000D03*
Y42000D03*
X878992Y61508D03*
X903000Y61500D03*
X906200Y85270D03*
X896500Y342500D03*
X898817Y311761D03*
X887500Y312000D03*
X896200Y358300D03*
X896500Y350200D03*
X879816Y755877D03*
X888087Y758068D03*
X894108Y790279D03*
X898700Y788300D03*
X879696Y792164D03*
X890049Y793216D03*
X928398Y70962D03*
X940377Y81913D03*
X922015Y83123D03*
X929060Y82741D03*
X934779Y82801D03*
X915908Y83067D03*
X910754Y81409D03*
X937400Y76700D03*
X925300Y78500D03*
X950120Y63525D03*
X942500Y102500D03*
X947000Y106000D03*
X953000Y108000D03*
X960522Y89645D03*
X945590Y82830D03*
X950970Y82791D03*
X956313Y81319D03*
X992540Y18675D03*
X992002Y37056D03*
X1000480Y41812D03*
X1004765Y49647D03*
X1033747Y20176D03*
X1036692Y38477D03*
X1028900Y56100D03*
X1028815Y41714D03*
X1042600Y46100D03*
X1026500Y75500D03*
X1031400Y112500D03*
X1069131Y7363D03*
X1071559Y35329D03*
X1043650Y15633D03*
X1045000Y64500D03*
X1060000Y74000D03*
X1049500Y45000D03*
X1050216Y50022D03*
X1051850Y75550D03*
X1057431Y89182D03*
X1071330Y132580D03*
X1097000Y1500D03*
X1083235Y5000D03*
X1086613Y31774D03*
X1090929Y9074D03*
X1078000Y72500D03*
X1120205Y239021D03*
X1127500Y234500D03*
X1134187Y238517D03*
X1141500Y234000D03*
X1155000Y242000D03*
X1156000Y234500D03*
X1167500Y294500D03*
X1172500Y742500D03*
X1169000Y750500D03*
X1165375Y757000D03*
X1189600Y244600D03*
X1220164Y204033D03*
X1257500Y378500D03*
X1262600Y346000D03*
X1269940D03*
X1278000Y385500D03*
X1273400Y383500D03*
X1268400Y386100D03*
X1266513Y397500D03*
X1261600Y386500D03*
X1273500Y448500D03*
X1299933Y129548D03*
X1305710Y144320D03*
X1295600Y305182D03*
X1285760Y347120D03*
X1284000Y604000D03*
X1311017Y673086D03*
X1306623Y722399D03*
X1301625Y722567D03*
X1314930Y126650D03*
X1319875Y135104D03*
X1316049Y120821D03*
X1329618Y135248D03*
X1325161Y279162D03*
X1329579Y672408D03*
X1316216Y673308D03*
X1333052Y686020D03*
X1319500Y726000D03*
Y737000D03*
Y731500D03*
X1329500Y721500D03*
X1378998Y168228D03*
X1371541Y166287D03*
X1362239Y262939D03*
X1356400Y282400D03*
X1350186Y280040D03*
X1348669Y704831D03*
X1383108Y198473D03*
X1383340Y177216D03*
G54D149*
X943111Y5908D03*
X935236D03*
X927361D03*
X919486D03*
X911616D03*
X943111Y13778D03*
X935236D03*
X927361D03*
X919486D03*
X911616D03*
X958856Y5908D03*
X950986D03*
X958856Y13778D03*
X950986D03*
G54D66*
X83667Y378687D03*
X79792Y371187D03*
X75917Y378687D03*
X112122Y378656D03*
X108247Y371156D03*
X104372Y378656D03*
X469145Y137332D03*
X465270Y129832D03*
X461395Y137332D03*
X464660Y153259D03*
X460785Y145759D03*
X456910Y153259D03*
X499278Y159142D03*
X495403Y151642D03*
X491528Y159142D03*
X513278D03*
X509403Y151642D03*
X505528Y159142D03*
X663756Y204942D03*
X659881Y197442D03*
X656006Y204942D03*
X670006D03*
X691756D03*
X687881Y197442D03*
X684006Y204942D03*
X677756D03*
X673881Y197442D03*
X1121500Y221250D03*
X1125375Y228750D03*
X1117625D03*
X1136000Y221250D03*
X1139875Y228750D03*
X1132125D03*
X1150500Y221250D03*
X1154375Y228750D03*
X1146625D03*
X1301543Y152335D03*
X1305418Y159835D03*
X1297668D03*
X1325530Y140759D03*
X1325220Y121870D03*
X1329095Y129370D03*
X1321345D03*
X1329405Y148259D03*
X1321655D03*
G54D93*
X154369Y286183D03*
X140069D03*
G54D84*
X103200Y782300D03*
X108200D03*
X113200D03*
X118200D03*
G54D48*
X58705Y280483D03*
X60673D03*
X62642D03*
Y315317D03*
X60673D03*
X58705D03*
X64610Y280483D03*
X66579D03*
X68547D03*
X70516D03*
X72484D03*
X74453D03*
X76421D03*
X78390D03*
X80358D03*
X82327D03*
X84295D03*
X78390Y315317D03*
X76421D03*
X74453D03*
X72484D03*
X70516D03*
X68547D03*
X66579D03*
X64610D03*
X84295D03*
X82327D03*
X80358D03*
G54D57*
X64350Y741790D03*
Y728010D03*
X44250D03*
Y741790D03*
G54D159*
X1337000Y263250D03*
G54D39*
X41603Y177598D03*
X65579D03*
X57587D03*
X49595D03*
X45559Y187598D03*
X37567D03*
X53551D03*
X73571Y177598D03*
X81563D03*
X77607Y187598D03*
X69615D03*
X85599D03*
G54D75*
X86678Y722200D03*
Y720600D03*
G54D85*
X104750Y813797D03*
Y820203D03*
G54D58*
X64050Y739821D03*
Y737853D03*
Y735884D03*
Y733916D03*
Y731947D03*
Y729979D03*
X44550D03*
Y731947D03*
Y733916D03*
Y735884D03*
Y737853D03*
Y739821D03*
G54D76*
X83922Y721400D03*
G54D49*
X31600Y321200D03*
X46900Y394400D03*
X90830Y273800D03*
X68300Y417000D03*
X91285Y489504D03*
Y486004D03*
X79300Y719300D03*
X104400Y306700D03*
X112351Y638436D03*
X127700Y714300D03*
Y710800D03*
X146869Y640420D03*
X146851Y648436D03*
X137351Y643936D03*
X146851D03*
X181421Y598436D03*
X281300Y122000D03*
X278100Y634900D03*
X328892Y295900D03*
X319300Y534500D03*
X623363Y213608D03*
X891200Y51500D03*
X908300Y45000D03*
Y48500D03*
X945581Y25374D03*
X1022663Y17398D03*
X1080300Y57000D03*
Y60500D03*
Y53500D03*
Y50000D03*
X1129700Y129800D03*
Y133300D03*
X1320800Y286500D03*
G54D67*
X90093Y371207D03*
X93968Y378707D03*
X97843Y371207D03*
X85950Y695400D03*
X82075Y687900D03*
X89825D03*
X96075D03*
X99950Y695400D03*
X103825Y687900D03*
X218979Y145011D03*
X222854Y152511D03*
X226729Y145011D03*
X1364343Y173852D03*
X1372093D03*
X1368218Y181352D03*
G54D94*
X143000Y388000D03*
G54D86*
X121480Y827000D03*
X135320D03*
G54D68*
X95148Y399115D03*
X90028D03*
Y405615D03*
X92588D03*
X95148D03*
X76829Y592970D03*
X71709D03*
Y599470D03*
X74269D03*
X76829D03*
X86940Y635250D03*
X92060D03*
Y628750D03*
X89500D03*
X86940D03*
X107368Y399042D03*
X102248D03*
Y405542D03*
X104808D03*
X107368D03*
X296122Y490150D03*
X293562D03*
X291002D03*
Y483650D03*
X296122D03*
G54D95*
X150000Y392921D03*
Y390953D03*
Y388984D03*
Y387016D03*
Y385047D03*
Y383079D03*
X136000D03*
Y385047D03*
Y387016D03*
Y388984D03*
Y390953D03*
Y392921D03*
G54D59*
X61190Y724850D03*
X47410D03*
Y744950D03*
X61190D03*
X562501Y351980D03*
X560531D03*
X558561D03*
X556596D03*
Y364180D03*
X558561D03*
X560531D03*
X562501D03*
X564466Y351980D03*
Y364180D03*
G54D77*
X97248Y813797D03*
Y820203D03*
G54D78*
X122165Y142874D03*
X173897D03*
G54D87*
X115355Y887120D03*
X285433D03*
X532678D03*
X702756D03*
X1028741D03*
X1198819D03*
G54D96*
X145965Y380050D03*
X140047Y395950D03*
Y380050D03*
X145953Y395950D03*
G54D69*
X96860Y494107D03*
Y496307D03*
G54D88*
X118504Y887970D03*
X121654D03*
X124803D03*
X127953D03*
X131103D03*
X134252D03*
X137402D03*
X140551D03*
X143701D03*
X146851D03*
X150000D03*
X153150D03*
X156300D03*
X159449D03*
X162599D03*
X165748D03*
X168898D03*
X172048D03*
X175197D03*
X178347D03*
X181496D03*
X184646D03*
X187796D03*
X190945D03*
X194095D03*
X197244D03*
X200394D03*
X203544D03*
X206693D03*
X209843D03*
X212992D03*
X216142D03*
X219292D03*
X222441D03*
X225591D03*
X228740D03*
X231890D03*
X235040D03*
X238189D03*
X241339D03*
X244488D03*
X247638D03*
X250788D03*
X253937D03*
X257087D03*
X260237D03*
X263386D03*
X266536D03*
X269685D03*
X272835D03*
X275985D03*
X279134D03*
X282284D03*
X288583D03*
X304331D03*
X307481D03*
X310630D03*
X313780D03*
X316929D03*
X320079D03*
X323229D03*
X326378D03*
X329528D03*
X332677D03*
X335827D03*
X338977D03*
X342126D03*
X345276D03*
X348426D03*
X351575D03*
X354725D03*
X357874D03*
X361024D03*
X364174D03*
X367323D03*
X370473D03*
X373622D03*
X376772D03*
X379922D03*
X383071D03*
X386221D03*
X389370D03*
X392520D03*
X395670D03*
X398819D03*
X401969D03*
X405118D03*
X408268D03*
X411418D03*
X414567D03*
X417717D03*
X420866D03*
X424016D03*
X427166D03*
X430315D03*
X433465D03*
X436614D03*
X439764D03*
X535827D03*
X538977D03*
X542126D03*
X545276D03*
X548426D03*
X551575D03*
X554725D03*
X557874D03*
X561024D03*
X564174D03*
X567323D03*
X570473D03*
X573623D03*
X576772D03*
X579922D03*
X583071D03*
X586221D03*
X589371D03*
X592520D03*
X595670D03*
X598819D03*
X601969D03*
X605119D03*
X608268D03*
X611418D03*
X614567D03*
X617717D03*
X620867D03*
X624016D03*
X627166D03*
X630315D03*
X633465D03*
X636615D03*
X639764D03*
X642914D03*
X646063D03*
X649213D03*
X652363D03*
X655512D03*
X658662D03*
X661811D03*
X664961D03*
X668111D03*
X671260D03*
X674410D03*
X677560D03*
X680709D03*
X683859D03*
X687008D03*
X690158D03*
X693308D03*
X696457D03*
X699607D03*
X705906D03*
X721654D03*
X724804D03*
X727953D03*
X731103D03*
X734252D03*
X737402D03*
X740552D03*
X743701D03*
X746851D03*
X750000D03*
X753150D03*
X756300D03*
X759449D03*
X762599D03*
X765749D03*
X768898D03*
X772048D03*
X775197D03*
X778347D03*
X781497D03*
X784646D03*
X787796D03*
X790945D03*
X794095D03*
X797245D03*
X800394D03*
X803544D03*
X806693D03*
X809843D03*
X812993D03*
X816142D03*
X819292D03*
X822441D03*
X825591D03*
X828741D03*
X831890D03*
X835040D03*
X838189D03*
X841339D03*
X844489D03*
X847638D03*
X850788D03*
X853937D03*
X857087D03*
X1031890D03*
X1035040D03*
X1038189D03*
X1041339D03*
X1044489D03*
X1047638D03*
X1050788D03*
X1053937D03*
X1057087D03*
X1060237D03*
X1063386D03*
X1066536D03*
X1069686D03*
X1072835D03*
X1075985D03*
X1079134D03*
X1082284D03*
X1085434D03*
X1088583D03*
X1091733D03*
X1094882D03*
X1098032D03*
X1101182D03*
X1104331D03*
X1107481D03*
X1110630D03*
X1113780D03*
X1116930D03*
X1120079D03*
X1123229D03*
X1126378D03*
X1129528D03*
X1132678D03*
X1135827D03*
X1138977D03*
X1142126D03*
X1145276D03*
X1148426D03*
X1151575D03*
X1154725D03*
X1157874D03*
X1161024D03*
X1164174D03*
X1167323D03*
X1170473D03*
X1173623D03*
X1176772D03*
X1179922D03*
X1183071D03*
X1186221D03*
X1189371D03*
X1192520D03*
X1195670D03*
X1201969D03*
X1217717D03*
X1220867D03*
X1224016D03*
X1227166D03*
X1230315D03*
X1233465D03*
X1236615D03*
X1239764D03*
X1242914D03*
X1246063D03*
X1249213D03*
X1252363D03*
X1255512D03*
X1258662D03*
X1261812D03*
X1264961D03*
X1268111D03*
X1271260D03*
X1274410D03*
X1277560D03*
X1280709D03*
X1283859D03*
X1287008D03*
X1290158D03*
X1293308D03*
X1296457D03*
X1299607D03*
X1302756D03*
X1305906D03*
X1309056D03*
X1312205D03*
X1315355D03*
X1318504D03*
X1321654D03*
X1324804D03*
X1327953D03*
X1331103D03*
X1334252D03*
X1337402D03*
X1340552D03*
X1343701D03*
X1346851D03*
X1350000D03*
X1353150D03*
G54D97*
X161050Y734560D03*
Y737120D03*
Y739680D03*
Y742240D03*
X153850Y789660D03*
Y792220D03*
Y794780D03*
Y797340D03*
X193350Y710660D03*
Y713220D03*
Y715780D03*
Y718340D03*
X177350Y742240D03*
Y739680D03*
Y737120D03*
Y734560D03*
X193350Y766160D03*
Y768720D03*
Y771280D03*
Y773840D03*
X170150Y797340D03*
Y794780D03*
Y792220D03*
Y789660D03*
X209650Y713220D03*
Y710660D03*
Y718340D03*
Y715780D03*
Y773840D03*
Y771280D03*
Y768720D03*
Y766160D03*
X470050Y374460D03*
Y377020D03*
Y379580D03*
Y382140D03*
X486350Y377020D03*
Y374460D03*
Y382140D03*
Y379580D03*
G54D79*
X134251Y153543D03*
X161811D03*
X151968D03*
X144094D03*
G54D89*
X164400Y204500D03*
X139600D03*
G54D98*
X167484Y186086D03*
Y182286D03*
X174084Y186086D03*
Y182286D03*
G54D99*
X196018Y209858D03*
X191018D03*
Y241354D03*
X196018D03*
X206018Y209858D03*
X201018D03*
Y241354D03*
X206018D03*
X534526Y248913D03*
X529526D03*
X524526D03*
X519526D03*
Y280409D03*
X524526D03*
X529526D03*
X534526D03*
M02*
